G04 ================== begin FILE IDENTIFICATION RECORD ==================*
G04 Layout Name:  13948-1b.brd*
G04 Film Name:    DIF_REF_L6*
G04 File Format:  Gerber RS274X*
G04 File Origin:  Cadence Allegro 16.5-S045*
G04 Origin Date:  Thu Nov 13 15:49:17 2014*
G04 *
G04 Layer:  BOARD GEOMETRY/OUTLINE*
G04 Layer:  BOARD GEOMETRY/DIF_REF_L6*
G04 Layer:  BOARD GEOMETRY/PANEL_OUTLINE*
G04 *
G04 Offset:    (0.00 0.00)*
G04 Mirror:    No*
G04 Mode:      Positive*
G04 Rotation:  0*
G04 FullContactRelief:  No*
G04 UndefLineWidth:     6.00*
G04 ================== end FILE IDENTIFICATION RECORD ====================*
%FSLAX35Y35*MOIN*%
%IR0*IPPOS*OFA0.00000B0.00000*MIA0B0*SFA1.00000B1.00000*%
%ADD10C,.004*%
%ADD11C,.005*%
%ADD12C,.006*%
%ADD13C,.0035*%
G75*
%LPD*%
G75*
G54D10*
G01X116200Y412800D02*
X44096Y484904D01*
G01X43176Y483984D02*
X47580Y479580D01*
G01D02*
X115281Y411880D01*
G01X50700Y598699D02*
Y492401D01*
G01D02*
G03X53484Y485676I9509J-2D01*
G01X44096Y484904D02*
G02X39500Y496000I11096J11096D01*
G01D02*
Y598728D01*
G01X38200Y598727D02*
Y496001D01*
G01D02*
G03X43176Y483984I16993J-2D01*
G01X53668Y605869D02*
G03X50700Y598699I7170J-7167D01*
G01X39500Y598728D02*
G02X43270Y607830I12872J0D01*
G01D02*
X72580Y637140D01*
G01X71660Y638059D02*
X42350Y608749D01*
G01D02*
G03X38200Y598727I10022J-10020D01*
G01X53484Y485676D02*
X60370Y478790D01*
G01D02*
G02X60684Y477846I-763J-778D01*
G01D02*
G03X60999Y476902I1078J-165D01*
G01D02*
X61848Y476054D01*
G01D02*
G03X62792Y475739I779J762D01*
G01D02*
G02X63736Y475424I165J-1077D01*
G01D02*
X64584Y474576D01*
G01D02*
G02X64899Y473632I-763J-779D01*
G01D02*
G03X65213Y472688I1077J-166D01*
G01D02*
X66062Y471839D01*
G01D02*
G03X67006Y471525I778J763D01*
G01D02*
G02X67950Y471210I165J-1078D01*
G01X131750Y409250D02*
X54404Y486596D01*
G01X141830Y412831D02*
X65430Y489230D01*
G01D02*
X64772Y489888D01*
G01D02*
G02X62200Y496101I6213J6211D01*
G01D02*
Y594107D01*
G01X63500Y594106D02*
Y496100D01*
G01D02*
G03X65692Y490808I7484J0D01*
G01D02*
X142750Y413750D01*
G01X54404Y486596D02*
G02X52000Y492400I5804J5804D01*
G01D02*
Y528492D01*
G01D02*
G02X52445Y529382I1090J11D01*
G01D02*
G03X52890Y530272I-645J879D01*
G01D02*
Y531472D01*
G01D02*
G03X52445Y532362I-1090J11D01*
G01D02*
G02X52000Y533252I645J879D01*
G01D02*
Y534452D01*
G01D02*
G02X52445Y535342I1090J11D01*
G01D02*
G03X52890Y536232I-645J879D01*
G01D02*
Y537432D01*
G01D02*
G03X52445Y538322I-1090J11D01*
G01D02*
G02X52000Y539212I645J879D01*
G01D02*
Y540412D01*
G01D02*
G02X52445Y541302I1090J11D01*
G01D02*
G03X52890Y542192I-645J879D01*
G01D02*
Y543392D01*
G01D02*
G03X52445Y544282I-1090J11D01*
G01D02*
G02X52000Y545172I645J879D01*
G01D02*
Y555191D01*
G01D02*
G02X52445Y556081I1090J11D01*
G01D02*
G03X52890Y556971I-645J879D01*
G01D02*
Y558171D01*
G01D02*
G03X52445Y559061I-1090J11D01*
G01D02*
G02X52000Y559951I645J879D01*
G01D02*
Y561151D01*
G01D02*
G02X52445Y562041I1090J11D01*
G01D02*
G03X52890Y562931I-645J879D01*
G01D02*
Y564131D01*
G01D02*
G03X52445Y565021I-1090J11D01*
G01D02*
G02X52000Y565911I645J879D01*
G01D02*
Y576356D01*
G01D02*
G02X52445Y577246I1090J11D01*
G01D02*
G03X52890Y578136I-645J879D01*
G01D02*
Y579336D01*
G01D02*
G03X52445Y580226I-1090J11D01*
G01D02*
G02X52000Y581116I645J879D01*
G01D02*
Y582316D01*
G01X62200Y594107D02*
G02X64980Y600819I9494J-1D01*
G01X65900Y599900D02*
G03X63500Y594106I5794J-5794D01*
G01X52000Y582316D02*
G02X52445Y583206I1090J11D01*
G01D02*
G03X52890Y584096I-645J879D01*
G01D02*
Y585296D01*
G01D02*
G03X52445Y586186I-1090J11D01*
G01D02*
G02X52000Y587076I645J879D01*
G01D02*
Y598700D01*
G01X64980Y600819D02*
Y600820D01*
G01D02*
X101580Y637420D01*
G01X102500Y636500D02*
X65900Y599900D01*
G01X93650Y645850D02*
X53699Y605899D01*
G01D02*
Y605900D01*
G01D02*
X53668Y605869D01*
G01X52000Y598700D02*
G02X54588Y604949I8838J0D01*
G01D02*
X65716Y616077D01*
G01D02*
X65717D01*
G01D02*
G02X66661Y616392I779J-763D01*
G01D02*
G03X67605Y616706I166J1077D01*
G01X71220Y467310D02*
G02X72164Y466996I166J-1077D01*
G01D02*
X86713Y452447D01*
G01X153631Y413030D02*
X76979Y489681D01*
G01X67950Y471210D02*
X68798Y470362D01*
G01D02*
G02X69113Y469418I-762J-779D01*
G01D02*
G03X69428Y468474I1077J-165D01*
G01D02*
X70276Y467625D01*
G01D02*
G03X71220Y467310I779J763D01*
G01X76979Y489681D02*
G02X73700Y497601I7920J7918D01*
G01D02*
Y596034D01*
G01X75000Y596035D02*
Y497600D01*
G01D02*
G03X77899Y490601I9898J0D01*
G01D02*
X154550Y413950D01*
G01X73700Y596034D02*
G02X76531Y602870I9665J2D01*
G01X77450Y601950D02*
G03X75000Y596035I5915J-5915D01*
G01X76531Y602870D02*
X76530D01*
G01D02*
X104513Y630853D01*
G01X105433Y629933D02*
X77450Y601950D01*
G01X67605Y616706D02*
X68454Y617555D01*
G01D02*
G03X68768Y618499I-763J778D01*
G01D02*
G02X69083Y619443I1078J165D01*
G01D02*
X69931Y620291D01*
G01D02*
G02X70875Y620606I779J-762D01*
G01D02*
G03X71819Y620921I165J1077D01*
G01D02*
X72668Y621769D01*
G01D02*
G03X72983Y622713I-763J779D01*
G01D02*
G02X73297Y623657I1077J166D01*
G01D02*
X81127Y631487D01*
G01D02*
G02X82071Y631802I779J-762D01*
G01D02*
G03X83015Y632117I165J1077D01*
G01D02*
X83864Y632965D01*
G01X72580Y637140D02*
G02X73524Y637454I778J-763D01*
G01D02*
G03X74468Y637769I165J1078D01*
G01D02*
X75316Y638617D01*
G01D02*
G03X75631Y639561I-763J779D01*
G01D02*
G02X75945Y640505I1077J166D01*
G01D02*
X76794Y641354D01*
G01D02*
G02X77738Y641669I779J-763D01*
G01D02*
G03X78682Y641983I166J1077D01*
G01D02*
X79530Y642832D01*
G01D02*
G03X79845Y643776I-762J779D01*
G01D02*
G02X80160Y644720I1078J165D01*
G01D02*
X81008Y645568D01*
G01D02*
G02X81952Y645883I779J-762D01*
G01D02*
G03X82896Y646198I165J1077D01*
G01D02*
X83745Y647046D01*
G01X86200Y652600D02*
X71660Y638060D01*
G01D02*
Y638059D01*
G01X87028Y451503D02*
G03X87343Y450559I1077J-165D01*
G01D02*
X88191Y449710D01*
G01D02*
G03X89135Y449396I778J763D01*
G01D02*
G02X90079Y449081I165J-1077D01*
G01D02*
X90928Y448233D01*
G01D02*
G02X91243Y447289I-763J-779D01*
G01D02*
G03X91557Y446345I1077J-166D01*
G01D02*
X92406Y445496D01*
G01D02*
G03X93350Y445182I778J763D01*
G01D02*
G02X94294Y444867I165J-1078D01*
G01D02*
X95142Y444018D01*
G01D02*
G02X95457Y443074I-762J-779D01*
G01D02*
G03X95772Y442130I1077J-165D01*
G01D02*
X96620Y441282D01*
G01D02*
G03X97564Y440967I779J763D01*
G01D02*
G02X98508Y440653I166J-1077D01*
G01D02*
X106688Y432473D01*
G01X86713Y452447D02*
G02X87028Y451503I-762J-779D01*
G01X162881Y415780D02*
X89850Y488810D01*
G01X163800Y416700D02*
X90770Y489730D01*
G01X89850Y488810D02*
G02X86500Y496899I8091J8089D01*
G01D02*
Y599616D01*
G01X90770Y489730D02*
G02X87800Y496900I7170J7170D01*
G01D02*
Y599617D01*
G01X171477Y419522D02*
X99316Y491684D01*
G01D02*
G02X96700Y498000I6317J6316D01*
G01D02*
Y538189D01*
G01X170557Y418602D02*
X98396Y490764D01*
G01D02*
G02X95400Y497999I7237J7235D01*
G01D02*
Y598663D01*
G01X96700Y538189D02*
G02X97145Y539079I1090J11D01*
G01D02*
G03X97590Y539969I-645J879D01*
G01D02*
Y541169D01*
G01D02*
G03X97145Y542059I-1090J11D01*
G01D02*
G02X96700Y542949I645J879D01*
G01D02*
Y544149D01*
G01D02*
G02X97145Y545039I1090J11D01*
G01D02*
G03X97590Y545929I-645J879D01*
G01D02*
Y547129D01*
G01D02*
G03X97145Y548019I-1090J11D01*
G01D02*
G02X96700Y548909I645J879D01*
G01D02*
Y550109D01*
G01D02*
G02X97145Y550999I1090J11D01*
G01D02*
G03X97590Y551889I-645J879D01*
G01D02*
Y553089D01*
G01D02*
G03X97145Y553979I-1090J11D01*
G01D02*
G02X96700Y554869I645J879D01*
G01D02*
Y598664D01*
G01X86500Y599616D02*
G02X89131Y605969I8982J1D01*
G01D02*
X89130D01*
G01D02*
X107081Y623920D01*
G01X87800Y599617D02*
G02X90050Y605049I7682J0D01*
G01D02*
X108001Y623000D01*
G01X96700Y598664D02*
G02X99200Y604700I8536J0D01*
G01D02*
X110250Y615750D01*
G01X95400Y598663D02*
G02X98281Y605620I9836J2D01*
G01D02*
X98280D01*
G01D02*
X109328Y616668D01*
G01X172900Y647500D02*
X97635D01*
G01D02*
G03X93651Y645850I1J-5636D01*
G01D02*
X93650D01*
G01X83864Y632965D02*
G03X84178Y633909I-763J778D01*
G01D02*
G02X84493Y634853I1078J165D01*
G01D02*
X85342Y635702D01*
G01D02*
G02X86286Y636016I778J-763D01*
G01D02*
G03X87230Y636331I165J1078D01*
G01D02*
X88078Y637179D01*
G01D02*
G03X88393Y638123I-763J779D01*
G01D02*
G02X88707Y639067I1077J166D01*
G01D02*
X89556Y639916D01*
G01D02*
G02X90500Y640231I779J-763D01*
G01D02*
G03X91444Y640545I166J1077D01*
G01D02*
X92292Y641394D01*
G01D02*
G03X92607Y642338I-762J779D01*
G01D02*
G02X92922Y643282I1077J165D01*
G01D02*
X94570Y644930D01*
G01D02*
G02X97636Y646200I3066J-3066D01*
G01D02*
X172899D01*
G01X83745Y647046D02*
G03X84060Y647990I-763J779D01*
G01D02*
G02X84374Y648934I1077J166D01*
G01D02*
X87120Y651680D01*
G01D02*
G02X93445Y654300I6325J-6325D01*
G01D02*
X173268D01*
G01X173264Y655600D02*
X93444D01*
G01D02*
G03X86201Y652600I1J-10245D01*
G01D02*
X86200D01*
G01X122000Y398797D02*
G03X116200Y412800I-19802J1D01*
G01X115281Y411880D02*
G02X120700Y398797I-13083J-13083D01*
G01X106688Y432473D02*
G02X107002Y431529I-763J-778D01*
G01D02*
G03X107317Y430585I1078J-165D01*
G01D02*
X108166Y429737D01*
G01D02*
G03X109110Y429422I779J762D01*
G01D02*
G02X110054Y429107I165J-1077D01*
G01D02*
X110902Y428259D01*
G01D02*
G02X111217Y427315I-763J-779D01*
G01D02*
G03X111531Y426371I1077J-166D01*
G01D02*
X112380Y425522D01*
G01D02*
G03X113324Y425208I778J763D01*
G01D02*
G02X114268Y424893I165J-1078D01*
G01D02*
X115116Y424045D01*
G01D02*
G02X115431Y423101I-762J-779D01*
G01D02*
G03X115746Y422157I1077J-165D01*
G01D02*
X116594Y421308D01*
G01X176201Y422960D02*
X106284Y492876D01*
G01X179078Y430581D02*
X114330Y495330D01*
G01D02*
X114331D01*
G01D02*
G02X111000Y503373I8041J8041D01*
G01X179998Y431501D02*
X115250Y496250D01*
G01D02*
G02X112300Y503372I7122J7122D01*
G01X177121Y423880D02*
X107204Y493796D01*
G01D02*
G02X104800Y499600I5804J5804D01*
G01D02*
Y597100D01*
G01X106284Y492876D02*
G02X103500Y499601I6724J6722D01*
G01D02*
Y597101D01*
G01X111000Y503373D02*
Y593345D01*
G01X112300Y503372D02*
Y593344D01*
G01X111000Y593345D02*
G02X115000Y603000I13657J-2D01*
G01X112300Y593344D02*
G02X115920Y602080I12356J-2D01*
G01X104800Y597100D02*
G02X107416Y603416I8933J0D01*
G01X103500Y597101D02*
G02X106496Y604336I10234J0D01*
G01X115000Y603000D02*
G02X121036Y605500I6036J-6036D01*
G01X115920Y602080D02*
G02X121036Y604200I5117J-5115D01*
G01X107416Y603416D02*
X113750Y609750D01*
G01D02*
G02X117251Y611200I3501J-3501D01*
G01X106496Y604336D02*
X112830Y610670D01*
G01D02*
G02X117252Y612500I4419J-4422D01*
G01X107081Y623920D02*
G02X112103Y626000I5023J-5024D01*
G01D02*
X189800D01*
G01X108001Y623000D02*
G02X112104Y624700I4104J-4104D01*
G01D02*
X189799D01*
G01X110250Y615750D02*
X110619Y616120D01*
G01D02*
G02X115000Y617934I4380J-4381D01*
G01D02*
X199299D01*
G01X109328Y616668D02*
X109329D01*
G01D02*
X109699Y617039D01*
G01D02*
G02X115000Y619235I5301J-5300D01*
G01D02*
Y619234D01*
G01D02*
X199300D01*
G01X104513Y630853D02*
G02X110421Y633300I5908J-5908D01*
G01Y632000D02*
G03X105433Y629933I1J-7054D01*
G01X110421Y633300D02*
X184100D01*
G01X184099Y632000D02*
X110421D01*
G01X101580Y637420D02*
X101581D01*
G01D02*
G02X107851Y640017I6271J-6272D01*
G01D02*
X178954D01*
G01X178955Y638717D02*
X107852D01*
G01D02*
G03X102500Y636500I0J-7569D01*
G01X131147Y354709D02*
X131020D01*
G01D02*
G02X130291Y355196I0J789D01*
G01D02*
X130118Y355614D01*
G01D02*
G02X130000Y356209I1438J594D01*
G01D02*
Y365050D01*
G01D02*
G03X126500Y373500I-11950J0D01*
G01X125580Y372580D02*
G02X128699Y365050I-7530J-7530D01*
G01D02*
X128700Y358000D01*
G01D02*
G02X127362Y354770I-4568J0D01*
G01D02*
X127301Y354709D01*
G01X126500Y373500D02*
G02X122000Y384364I10864J10864D01*
G01D02*
Y398797D01*
G01X120700D02*
Y384364D01*
G01D02*
G03X125580Y372580I16665J-1D01*
G01X132700Y403818D02*
Y392073D01*
G01D02*
G03X139142Y376518I21998J-1D01*
G01X118482Y420679D02*
X130831Y408330D01*
G01D02*
G02X132700Y403818I-4513J-4512D01*
G01X134000D02*
G03X131750Y409250I-7682J0D01*
G01X116594Y421308D02*
G03X117538Y420993I779J763D01*
G01D02*
G02X118482Y420679I166J-1077D01*
G01X121036Y605500D02*
X213700D01*
G01X121036Y604200D02*
X213701D01*
G01X117251Y611200D02*
X204783D01*
G01X117252Y612500D02*
X204782D01*
G01X140700Y373378D02*
Y356554D01*
G01D02*
G02X140385Y355793I-1077J0D01*
G01D02*
X139301Y354709D01*
G01X143147D02*
X143019D01*
G01D02*
G02X142800Y354800I0J309D01*
G01D02*
X142446Y355155D01*
G01D02*
G02X142000Y356230I1075J1076D01*
G01D02*
Y373379D01*
G01X149580Y376580D02*
G02X144700Y388364I11785J11783D01*
G01X146000D02*
G03X150500Y377500I15364J0D01*
G01X139142Y376518D02*
X139580Y376080D01*
G01D02*
G02X140700Y373378I-2700J-2702D01*
G01X142000Y373379D02*
G03X140500Y377000I-5121J0D01*
G01D02*
X140062Y377438D01*
G01D02*
G02X134000Y392073I14635J14635D01*
G01X144700Y388364D02*
Y405903D01*
G01X146000Y405904D02*
Y388364D01*
G01X134000Y392073D02*
Y403818D01*
G01X144700Y405903D02*
G03X141830Y412831I-9796J0D01*
G01X142750Y413750D02*
G02X146000Y405904I-7846J-7846D01*
G01X164147Y328699D02*
X164759Y329311D01*
G01D02*
G03X165200Y330376I-1065J1065D01*
G01D02*
Y334439D01*
G01D02*
G02X166330Y337170I3862J2D01*
G01X162801Y354709D02*
X163385Y355293D01*
G01D02*
G03X163700Y356054I-762J761D01*
G01D02*
Y368878D01*
G01X165000Y368879D02*
Y356500D01*
G01D02*
G03X165102Y356254I348J0D01*
G01D02*
X166647Y354709D01*
G01X151301D02*
X151885Y355293D01*
G01D02*
G03X152200Y356054I-762J761D01*
G01D02*
Y370258D01*
G01X153500Y370257D02*
Y356500D01*
G01D02*
G03X153602Y356254I348J0D01*
G01D02*
X155147Y354709D01*
G01X167266Y378895D02*
G02X165546Y383046I4150J4152D01*
G01D02*
Y409347D01*
G01X163700Y368878D02*
G03X162580Y371580I-3820J0D01*
G01D02*
G02X158527Y377186I15405J15405D01*
G01D02*
G02X156199Y386985I19458J9799D01*
G01X157500D02*
G03X159689Y377771I20485J0D01*
G01D02*
G03X163500Y372500I18296J9215D01*
G01D02*
G02X165000Y368879I-3621J-3621D01*
G01X152200Y370258D02*
X152199Y370257D01*
G01D02*
G03X149580Y376580I-8942J0D01*
G01X150500Y377500D02*
G02X153500Y370257I-7243J-7243D01*
G01X156199Y386985D02*
Y392073D01*
G01D02*
X156200Y392074D01*
G01D02*
Y406828D01*
G01X157500D02*
Y386985D01*
G01X165546Y409347D02*
X165545Y409346D01*
G01D02*
G03X162881Y415780I-9100J1D01*
G01X166846Y409346D02*
G03X163800Y416700I-10400J0D01*
G01X156200Y406828D02*
G03X153631Y413030I-8772J0D01*
G01X154550Y413950D02*
G02X157500Y406828I-7122J-7122D01*
G01X167993Y328699D02*
X167992D01*
G01D02*
G02X167326Y328975I1J944D01*
G01D02*
X167210Y329091D01*
G01D02*
G02X166500Y330802I1707J1711D01*
G01D02*
Y334439D01*
G01D02*
G02X167250Y336250I2561J0D01*
G01X179622Y328749D02*
X178466Y329905D01*
G01D02*
G02X178349Y330188I284J283D01*
G01D02*
Y331127D01*
G01D02*
X178300Y331176D01*
G01D02*
Y333965D01*
G01D02*
X178301Y333964D01*
G01D02*
G02X180420Y339080I7235J0D01*
G01X175776Y328749D02*
X176932Y329905D01*
G01D02*
G03X177049Y330188I-284J283D01*
G01D02*
Y330588D01*
G01D02*
X177000Y330637D01*
G01D02*
Y333964D01*
G01D02*
G02X179500Y340000I8536J0D01*
G01X166330Y337170D02*
X173873Y344713D01*
G01D02*
G03X174200Y345500I-787J788D01*
G01D02*
X174199Y364121D01*
G01X167250Y336250D02*
X174793Y343793D01*
G01D02*
G03X175500Y345500I-1707J1707D01*
G01D02*
Y365429D01*
G01X180420Y339080D02*
G03X184000Y347724I-8646J8644D01*
G01X179500Y340000D02*
G03X182700Y347725I-7725J7725D01*
G01X174199Y364121D02*
Y365427D01*
G01D02*
X174200Y365428D01*
G01D02*
G03X169580Y376580I-15770J0D01*
G01X175500Y365429D02*
G03X170500Y377500I-17071J0D01*
G01X169580Y376580D02*
X167266Y378895D01*
G01X170500Y377500D02*
X168186Y379815D01*
G01D02*
G02X166847Y383046I3231J3232D01*
G01D02*
X166846Y389086D01*
G01X184000Y367293D02*
G03X179370Y378471I-15808J0D01*
G01D02*
G02X174800Y389501I11028J11031D01*
G01X182699Y367293D02*
G03X178450Y377551I-14507J0D01*
G01D02*
G02X173500Y389500I11949J11950D01*
G01X185920Y381920D02*
G02X181800Y391864I9943J9945D01*
G01D02*
X181801Y409500D01*
G01X185000Y381000D02*
G02X180500Y391864I10864J10864D01*
G01D02*
Y412581D01*
G01X166846Y389086D02*
Y390770D01*
G01D02*
G02X167291Y391660I1090J11D01*
G01D02*
G03X167736Y392550I-645J879D01*
G01D02*
Y393750D01*
G01D02*
G03X167291Y394640I-1090J11D01*
G01D02*
G02X166846Y395530I645J879D01*
G01D02*
Y396730D01*
G01D02*
G02X167291Y397620I1090J11D01*
G01D02*
G03X167736Y398510I-645J879D01*
G01D02*
Y399710D01*
G01D02*
G03X167291Y400600I-1090J11D01*
G01D02*
G02X166846Y401490I645J879D01*
G01X174800Y389501D02*
Y411501D01*
G01X173500Y389500D02*
Y411500D01*
G01X181801Y409500D02*
X181800D01*
G01D02*
Y412580D01*
G01D02*
G03X177121Y423880I-15979J2D01*
G01X180500Y412581D02*
G03X176201Y422960I-14678J0D01*
G01X166846Y401490D02*
Y409346D01*
G01X174800Y411501D02*
G03X171477Y419522I-11344J-1D01*
G01X173500Y411500D02*
G03X170557Y418602I-10043J-1D01*
G01X187700Y411499D02*
G03X180303Y429356I-25253J0D01*
G01D02*
X179078Y430581D01*
G01X189000Y411500D02*
G03X181223Y430276I-26554J0D01*
G01D02*
X179998Y431501D01*
G01X178954Y640017D02*
G03X180722Y640749I0J2500D01*
G01D02*
X194487Y654514D01*
G01X187212Y645400D02*
X181642Y639830D01*
G01D02*
G02X178955Y638717I-2687J2687D01*
G01X178192Y649692D02*
G02X172900Y647500I-5292J5292D01*
G01X172899Y646200D02*
G03X179112Y648772I2J8785D01*
G01X189900Y661400D02*
X178192Y649692D01*
G01X179112Y648772D02*
X190820Y660480D01*
G01X173268Y654300D02*
G03X175955Y655413I0J3800D01*
G01D02*
X187163Y666624D01*
G01X186244Y667544D02*
X175032Y656332D01*
G01D02*
G02X173264Y655600I-1768J1768D01*
G01X184000Y347724D02*
Y367293D01*
G01X182700Y347725D02*
Y364800D01*
G01X200200Y359000D02*
G03X195391Y370609I-16417J0D01*
G01X182700Y364800D02*
X182699Y367293D01*
G01X208968Y367696D02*
X194329Y382335D01*
G01D02*
G02X187700Y398691I16863J16356D01*
G01X209887Y368617D02*
X195256Y383248D01*
G01D02*
G02X189000Y398692I15936J15444D01*
G01X201500Y359001D02*
G03X196311Y371529I-17718J0D01*
G01D02*
X185920Y381920D01*
G01X195391Y370609D02*
X185000Y381000D01*
G01X187700Y398691D02*
Y411499D01*
G01X189000Y398692D02*
Y411500D01*
G01X189800Y626000D02*
G03X191848Y626848I0J2897D01*
G01D02*
X204600Y639600D01*
G01X189799Y624700D02*
G03X192768Y625928I2J4198D01*
G01D02*
X197840Y631000D01*
G01D02*
G02X198784Y631315I779J-762D01*
G01X184100Y633300D02*
G03X188709Y635209I0J6518D01*
G01D02*
X201100Y647600D01*
G01X199050Y642451D02*
G02X198106Y642136I-779J763D01*
G01D02*
G03X197162Y641822I-166J-1077D01*
G01D02*
X196313Y640973D01*
G01D02*
G03X195998Y640029I763J-779D01*
G01D02*
G02X195684Y639085I-1077J-166D01*
G01D02*
X194835Y638237D01*
G01D02*
G02X193891Y637922I-779J762D01*
G01D02*
G03X193498Y637910I-164J-1077D01*
G01D02*
G03X192947Y637607I227J-1066D01*
G01D02*
X189629Y634289D01*
G01D02*
G02X184099Y632000I-5528J5530D01*
G01X190263Y647822D02*
G02X189948Y646878I-1077J-165D01*
G01D02*
X189100Y646029D01*
G01D02*
G02X188156Y645715I-778J763D01*
G01D02*
G03X187212Y645400I-165J-1078D01*
G01X194487Y654514D02*
G02X199323Y656517I4837J-4838D01*
G01X199324Y655217D02*
G03X195406Y653594I0J-5541D01*
G01D02*
X194792Y652980D01*
G01D02*
G03X194477Y652036I763J-779D01*
G01D02*
G02X194163Y651092I-1077J-166D01*
G01D02*
X193314Y650244D01*
G01D02*
G02X192370Y649929I-779J762D01*
G01D02*
G03X191426Y649614I-165J-1077D01*
G01D02*
X190578Y648766D01*
G01D02*
G03X190263Y647822I762J-779D01*
G01X482000Y664000D02*
X196177D01*
G01D02*
G03X189900Y661400I0J-8877D01*
G01X190820Y660480D02*
G02X196177Y662700I5358J-5356D01*
G01D02*
X481999D01*
G01X187163Y666624D02*
G02X194106Y669500I6943J-6943D01*
G01D02*
X485593D01*
G01X485594Y670800D02*
X194105D01*
G01D02*
G03X186244Y667544I1J-11119D01*
G01X208338Y323297D02*
X208752Y323711D01*
G01D02*
G03X209700Y326000I-2289J2289D01*
G01D02*
Y365928D01*
G01X212134Y323297D02*
X212129D01*
G01D02*
G02X211787Y323435I0J493D01*
G01D02*
X211685Y323533D01*
G01D02*
G02X211000Y325145I1553J1611D01*
G01D02*
Y331725D01*
G01D02*
G02X211445Y332615I1090J11D01*
G01D02*
G03X211890Y333505I-645J879D01*
G01D02*
Y334705D01*
G01D02*
G03X211445Y335595I-1090J11D01*
G01D02*
G02X211000Y336485I645J879D01*
G01X202710Y323297D02*
X202202Y323805D01*
G01D02*
G02X201500Y325500I1695J1695D01*
G01D02*
Y328262D01*
G01D02*
G02X201945Y329152I1090J11D01*
G01D02*
G03X202390Y330042I-645J879D01*
G01D02*
Y331242D01*
G01D02*
G03X201945Y332132I-1090J11D01*
G01D02*
G02X201500Y333022I645J879D01*
G01D02*
Y334222D01*
G01D02*
G02X201945Y335112I1090J11D01*
G01D02*
G03X202390Y336002I-645J879D01*
G01X198864Y323297D02*
X199587Y324020D01*
G01D02*
G03X200200Y325500I-1480J1480D01*
G01D02*
Y359000D01*
G01X211000Y336485D02*
Y337685D01*
G01D02*
G02X211445Y338575I1090J11D01*
G01D02*
G03X211890Y339465I-645J879D01*
G01D02*
Y340665D01*
G01D02*
G03X211445Y341555I-1090J11D01*
G01D02*
G02X211000Y342445I645J879D01*
G01D02*
Y365930D01*
G01X202390Y336002D02*
Y337202D01*
G01D02*
G03X201945Y338092I-1090J11D01*
G01D02*
G02X201500Y338982I645J879D01*
G01D02*
Y340182D01*
G01D02*
G02X201945Y341072I1090J11D01*
G01D02*
G03X202390Y341962I-645J879D01*
G01D02*
Y343162D01*
G01D02*
G03X201945Y344052I-1090J11D01*
G01D02*
G02X201500Y344942I645J879D01*
G01D02*
Y348691D01*
G01D02*
G02X201945Y349581I1090J11D01*
G01D02*
G03X202390Y350471I-645J879D01*
G01D02*
Y351671D01*
G01D02*
G03X201945Y352561I-1090J11D01*
G01X209700Y365928D02*
G03X208968Y367696I-2500J0D01*
G01X211000Y365930D02*
G03X209887Y368617I-3800J0D01*
G01X201945Y352561D02*
G02X201500Y353451I645J879D01*
G01D02*
Y359001D01*
G01X213700Y605500D02*
G03X217285Y606985I0J5070D01*
G01X213701Y604200D02*
G03X218205Y606065I0J6371D01*
G01X204783Y611200D02*
G03X212220Y614280I0J10519D01*
G01D02*
X223833Y625893D01*
G01X204782Y612500D02*
G03X211300Y615200I0J9218D01*
G01D02*
X222913Y626813D01*
G01X199299Y617934D02*
G03X201473Y618833I2J3073D01*
G01D02*
X216842Y634202D01*
G01X199300Y619234D02*
G03X200553Y619753I0J1772D01*
G01D02*
X215921Y635121D01*
G01X204600Y639600D02*
G02X213050Y643100I8450J-8450D01*
G01D02*
X475639D01*
G01X198784Y631315D02*
G03X199728Y631630I165J1077D01*
G01D02*
X200577Y632478D01*
G01D02*
G03X200892Y633422I-763J779D01*
G01D02*
G02X201206Y634366I1077J166D01*
G01D02*
X205520Y638680D01*
G01D02*
G02X213050Y641800I7531J-7529D01*
G01D02*
X475638D01*
G01X201100Y647600D02*
G02X206411Y649800I5311J-5311D01*
G01X206412Y648500D02*
G03X202020Y646680I0J-6210D01*
G01D02*
X200528Y645188D01*
G01D02*
G03X200213Y644244I762J-779D01*
G01D02*
G02X199898Y643300I-1077J-165D01*
G01D02*
X199050Y642451D01*
G01X206411Y649800D02*
X476200D01*
G01Y648500D02*
X206412D01*
G01X199323Y656517D02*
X481000D01*
G01X481001Y655217D02*
X199324D01*
G01X217285Y606985D02*
X231687Y621387D01*
G01X218205Y606065D02*
X232608Y620468D01*
G01X223833Y625893D02*
G02X229399Y628200I5568J-5566D01*
G01D02*
X468319D01*
G01X222913Y626813D02*
G02X229400Y629500I6487J-6487D01*
G01D02*
X468319D01*
G01X216842Y634202D02*
G02X218610Y634934I1768J-1768D01*
G01D02*
X471106D01*
G01X215921Y635121D02*
G02X218608Y636234I2687J-2687D01*
G01D02*
X471106D01*
G01X231687Y621387D02*
G02X234374Y622500I2687J-2687D01*
G01D02*
X464269D01*
G01X232608Y620468D02*
G02X234376Y621200I1768J-1768D01*
G01D02*
X464269D01*
G01X350169Y136832D02*
X327426Y159575D01*
G01D02*
G02X326840Y160990I1415J1415D01*
G01D02*
Y211401D01*
G01X328140Y175246D02*
Y160990D01*
G01D02*
G03X328346Y160495I701J1D01*
G01D02*
X335682Y153159D01*
G01X328140Y192542D02*
Y180006D01*
G01D02*
G03X328585Y179116I1090J-11D01*
G01D02*
G02X329030Y178226I-645J-879D01*
G01D02*
Y177026D01*
G01D02*
G02X328585Y176136I-1090J-11D01*
G01D02*
G03X328140Y175246I645J-879D01*
G01Y204462D02*
Y203262D01*
G01D02*
G03X328585Y202372I1090J-11D01*
G01D02*
G02X329030Y201482I-645J-879D01*
G01D02*
Y200282D01*
G01D02*
G02X328585Y199392I-1090J-11D01*
G01D02*
G03X328140Y198502I645J-879D01*
G01D02*
Y197302D01*
G01D02*
G03X328585Y196412I1090J-11D01*
G01D02*
G02X329030Y195522I-645J-879D01*
G01D02*
Y194322D01*
G01D02*
G02X328585Y193432I-1090J-11D01*
G01D02*
G03X328140Y192542I645J-879D01*
G01X326840Y211401D02*
G02X329603Y218073I9438J0D01*
G01D02*
X377965Y266435D01*
G01X330524Y217154D02*
G03X328140Y211400I5754J-5755D01*
G01D02*
Y209222D01*
G01D02*
G03X328585Y208332I1090J-11D01*
G01D02*
G02X329030Y207442I-645J-879D01*
G01D02*
Y206242D01*
G01D02*
G02X328585Y205352I-1090J-11D01*
G01D02*
G03X328140Y204462I645J-879D01*
G01X336263Y161635D02*
X357692Y140206D01*
G01X346465Y153903D02*
G03X346150Y154847I-1078J165D01*
G01D02*
X345302Y155695D01*
G01X335682Y153159D02*
G03X336626Y152845I778J763D01*
G01D02*
G02X337570Y152530I165J-1078D01*
G01D02*
X338418Y151681D01*
G01D02*
G02X338733Y150737I-762J-779D01*
G01D02*
G03X339048Y149793I1077J-165D01*
G01D02*
X339896Y148945D01*
G01D02*
G03X340840Y148630I779J763D01*
G01D02*
G02X341784Y148316I166J-1077D01*
G01D02*
X342633Y147467D01*
G01D02*
G02X342947Y146523I-763J-778D01*
G01D02*
G03X343262Y145579I1078J-165D01*
G01D02*
X344110Y144731D01*
G01D02*
G03X345054Y144416I779J762D01*
G01D02*
G02X345998Y144101I165J-1077D01*
G01D02*
X346847Y143253D01*
G01X334929Y210601D02*
Y164857D01*
G01D02*
G03X336263Y161636I4557J1D01*
G01D02*
Y161635D01*
G01X345302Y155695D02*
G03X344358Y156010I-779J-763D01*
G01D02*
G02X343414Y156324I-166J1077D01*
G01D02*
X337183Y162555D01*
G01D02*
G02X336229Y164858I2303J2303D01*
G01D02*
Y175094D01*
G01X343020Y196100D02*
Y167810D01*
G01D02*
G03X343226Y167314I702J1D01*
G01D02*
X352771Y157769D01*
G01X351500Y157200D02*
X342600Y166100D01*
G01D02*
X342307Y166394D01*
G01D02*
G02X341720Y167809I1415J1416D01*
G01D02*
Y196101D01*
G01X336229Y175094D02*
G02X336674Y175984I1090J11D01*
G01D02*
G03X337119Y176874I-645J879D01*
G01D02*
Y178074D01*
G01D02*
G03X336674Y178964I-1090J11D01*
G01D02*
G02X336229Y179854I645J879D01*
G01D02*
Y181054D01*
G01D02*
G02X336674Y181944I1090J11D01*
G01D02*
G03X337119Y182834I-645J879D01*
G01D02*
Y184034D01*
G01D02*
G03X336674Y184924I-1090J11D01*
G01D02*
G02X336229Y185814I645J879D01*
G01D02*
Y187014D01*
G01D02*
G02X336674Y187904I1090J11D01*
G01D02*
G03X337119Y188794I-645J879D01*
G01D02*
Y189994D01*
G01D02*
G03X336674Y190884I-1090J11D01*
G01D02*
G02X336229Y191774I645J879D01*
G01D02*
Y210600D01*
G01X347630Y207230D02*
G03X343020Y196100I11131J-11130D01*
G01X341720Y196101D02*
G02X346710Y208150I17042J0D01*
G01X376330Y254764D02*
X336882Y215316D01*
G01D02*
G03X334929Y210601I4716J-4715D01*
G01X336229Y210600D02*
G02X337802Y214396I5369J-1D01*
G01D02*
X345002Y221597D01*
G01X335542Y220914D02*
G02X334598Y220599I-779J763D01*
G01D02*
G03X333654Y220285I-166J-1077D01*
G01D02*
X330784Y217415D01*
G01D02*
X330524Y217154D01*
G01X345002Y221597D02*
X365021Y241616D01*
G01X378884Y265515D02*
X345448Y232079D01*
G01D02*
G03X345134Y231135I763J-778D01*
G01D02*
G02X344819Y230191I-1078J-165D01*
G01D02*
X343970Y229343D01*
G01D02*
G02X343026Y229028I-779J762D01*
G01D02*
G03X342082Y228713I-165J-1077D01*
G01D02*
X341234Y227865D01*
G01D02*
G03X340919Y226921I763J-779D01*
G01D02*
G02X340605Y225977I-1077J-166D01*
G01D02*
X339756Y225128D01*
G01D02*
G02X338812Y224814I-778J763D01*
G01D02*
G03X337868Y224499I-165J-1078D01*
G01D02*
X337020Y223651D01*
G01D02*
G03X336705Y222707I762J-779D01*
G01D02*
G02X336390Y221763I-1077J-165D01*
G01D02*
X335542Y220914D01*
G01X364000Y136246D02*
X351584D01*
G01D02*
G02X350169Y136832I0J2001D01*
G01X347476Y141365D02*
X351089Y137752D01*
G01D02*
G03X351584Y137546I496J495D01*
G01D02*
X365600D01*
G01X357692Y140206D02*
G03X359107Y139620I1415J1415D01*
G01D02*
X367776D01*
G01X366629Y140920D02*
X359107D01*
G01D02*
G02X358612Y141126I1J701D01*
G01D02*
X355208Y144530D01*
G01D02*
G02X354894Y145474I763J778D01*
G01D02*
G03X354579Y146418I-1078J165D01*
G01D02*
X353730Y147266D01*
G01D02*
G03X352786Y147581I-779J-762D01*
G01D02*
G02X351842Y147896I-165J1077D01*
G01D02*
X346779Y152959D01*
G01D02*
G02X346465Y153903I763J778D01*
G01X352771Y157769D02*
G02X354027Y154737I-3032J-3032D01*
G01D02*
Y153448D01*
G01D02*
G03X354929Y151272I3078J1D01*
G01D02*
X358500Y147700D01*
G01D02*
X359040Y147159D01*
G01D02*
Y147161D01*
G01D02*
X359421Y146779D01*
G01D02*
G03X360817Y146200I1396J1394D01*
G01D02*
X364350D01*
G01X364349Y144900D02*
X360816D01*
G01D02*
G02X358501Y145859I0J3274D01*
G01D02*
X357581Y146780D01*
G01D02*
X354009Y150352D01*
G01D02*
G02X352727Y153447I3096J3096D01*
G01D02*
Y154735D01*
G01D02*
G03X351852Y156849I-2989J1D01*
G01X361046Y153666D02*
X360656Y154056D01*
G01D02*
G02X360409Y154652I596J596D01*
G01D02*
Y160802D01*
G01X360126Y152747D02*
X359736Y153136D01*
G01D02*
Y153137D01*
G01D02*
G02X359109Y154651I1516J1515D01*
G01D02*
Y160802D01*
G01X346847Y143253D02*
G02X347162Y142309I-763J-779D01*
G01D02*
G03X347476Y141365I1077J-166D01*
G01X351852Y156849D02*
X351500Y157200D01*
G01X360409Y160802D02*
G03X359823Y162217I-2001J0D01*
G01D02*
X349926Y172114D01*
G01X359109Y160802D02*
G03X358904Y161297I-701J0D01*
G01D02*
X349007Y171194D01*
G01D02*
G02X348420Y172609I1415J1416D01*
G01X349926Y172114D02*
G02X349720Y172610I496J497D01*
G01D02*
Y196466D01*
G01X348420Y172609D02*
Y196466D01*
G01X349720D02*
G02X352073Y202144I8030J-1D01*
G01D02*
X392252Y242323D01*
G01X348420Y196466D02*
G02X351153Y203064I9331J0D01*
G01D02*
X391385Y243295D01*
G01X360400Y222660D02*
G02X358521Y218121I-6419J-1D01*
G01D02*
X357672Y217272D01*
G01D02*
G03X357358Y216328I763J-778D01*
G01D02*
G02X357043Y215384I-1078J-165D01*
G01D02*
X356195Y214536D01*
G01D02*
G02X355251Y214221I-779J763D01*
G01D02*
G03X354307Y213907I-166J-1077D01*
G01D02*
X347630Y207230D01*
G01X346710Y208150D02*
X357601Y219041D01*
G01D02*
G03X359100Y222660I-3619J3619D01*
G01X362893Y227824D02*
G03X361949Y227509I-165J-1077D01*
G01D02*
X360939Y226499D01*
G01D02*
G03X360401Y225200I1299J-1299D01*
G01D02*
X360400Y225201D01*
G01D02*
Y222660D01*
G01X359100D02*
Y225200D01*
G01D02*
G02X360019Y227419I3138J0D01*
G01D02*
X382800Y250200D01*
G01X371456Y136221D02*
X370787Y135552D01*
G01D02*
G02X368600Y134646I-2187J2187D01*
G01X366800D02*
G02X366038Y134961I-1J1077D01*
G01D02*
X366000Y135000D01*
G01D02*
X365287Y135713D01*
G01D02*
G03X364830Y136045I-1285J-1289D01*
G01D02*
G03X364000Y136246I-831J-1619D01*
G01X365600Y137546D02*
G02X367983Y136559I0J-3370D01*
G01D02*
X368296Y136246D01*
G01X367776Y139620D02*
G02X368305Y139401I0J-748D01*
G01X368314Y142505D02*
Y142385D01*
G01D02*
X367004Y141076D01*
G01D02*
G02X366629Y140920I-376J375D01*
G01X364350Y146200D02*
G02X366333Y145486I-1J-3113D01*
G01D02*
X367846D01*
G01D02*
G03X368314Y145680I0J662D01*
G01X371493Y145667D02*
Y145449D01*
G01D02*
G02X371100Y144500I-1342J0D01*
G01D02*
G02X370146Y144105I-954J954D01*
G01D02*
X368800D01*
G01X367100D02*
X366419D01*
G01D02*
G02X365504Y144484I0J1294D01*
G01D02*
G03X364349Y144900I-1156J-1397D01*
G01X373813Y238114D02*
X372965Y237266D01*
G01D02*
G02X372021Y236951I-779J763D01*
G01D02*
G03X371077Y236637I-166J-1077D01*
G01D02*
X370228Y235788D01*
G01D02*
G03X369913Y234844I763J-779D01*
G01D02*
G02X369599Y233900I-1077J-166D01*
G01D02*
X368750Y233052D01*
G01D02*
G02X367806Y232737I-779J762D01*
G01D02*
G03X366862Y232422I-165J-1077D01*
G01D02*
X365315Y230875D01*
G01D02*
G03X365001Y229931I763J-778D01*
G01D02*
G02X364686Y228987I-1078J-165D01*
G01D02*
X363837Y228139D01*
G01D02*
G02X362893Y227824I-779J762D01*
G01X365021Y241616D02*
G02X365965Y241931I779J-762D01*
G01D02*
G03X366909Y242246I165J1077D01*
G01D02*
X367758Y243094D01*
G01D02*
G03X368073Y244038I-763J779D01*
G01D02*
G02X368387Y244982I1077J166D01*
G01D02*
X369236Y245831D01*
G01D02*
G02X370180Y246145I778J-763D01*
G01D02*
G03X371124Y246460I165J1078D01*
G01D02*
X371972Y247309D01*
G01D02*
G03X372287Y248253I-762J779D01*
G01D02*
G02X372602Y249197I1077J165D01*
G01D02*
X377252Y253847D01*
G01X383720Y249280D02*
X378657Y244217D01*
G01D02*
G03X378342Y243273I763J-779D01*
G01D02*
G02X378028Y242329I-1077J-166D01*
G01D02*
X377179Y241481D01*
G01D02*
G02X376235Y241166I-779J762D01*
G01D02*
G03X375291Y240851I-165J-1077D01*
G01D02*
X374442Y240002D01*
G01D02*
G03X374128Y239058I763J-778D01*
G01D02*
G02X373813Y238114I-1078J-165D01*
G01X383900Y258001D02*
G03X376500Y254935I0J-10463D01*
G01D02*
X376330Y254764D01*
G01X377252Y253847D02*
X377421Y254017D01*
G01D02*
G02X383900Y256700I6478J-6479D01*
G01X377965Y266435D02*
G02X383675Y268800I5711J-5712D01*
G01X383676Y267500D02*
G03X378884Y265515I0J-6777D01*
G01X405297Y250000D02*
X391416D01*
G01D02*
G03X390526Y249555I-11J-1090D01*
G01D02*
G02X389636Y249110I-879J645D01*
G01D02*
X388436D01*
G01D02*
G02X387546Y249555I-11J1090D01*
G01D02*
G03X386656Y250000I-879J-645D01*
G01D02*
X385456D01*
G01D02*
G03X383720Y249280I1J-2455D01*
G01X382800Y250200D02*
G02X385456Y251300I2656J-2656D01*
G01D02*
X414002D01*
G01X392252Y242323D02*
X392253D01*
G01D02*
X392305Y242375D01*
G01D02*
G02X394501Y243285I2196J-2195D01*
G01D02*
X399093D01*
G01X391385Y243295D02*
G02X394500Y244585I3115J-3116D01*
G01D02*
X399092D01*
G01X410500Y258000D02*
X383900D01*
G01D02*
Y258001D01*
G01Y256700D02*
X410501D01*
G01X383675Y268800D02*
X411000D01*
G01Y267500D02*
X383676D01*
G01X414001Y250000D02*
X410057D01*
G01D02*
G03X409167Y249555I-11J-1090D01*
G01D02*
G02X408277Y249110I-879J645D01*
G01D02*
X407077D01*
G01D02*
G02X406187Y249555I-11J1090D01*
G01D02*
G03X405297Y250000I-879J-645D01*
G01X399093Y243285D02*
G02X400642Y242643I-1J-2193D01*
G01D02*
X400641Y242642D01*
G01D02*
X400803Y242481D01*
G01D02*
Y242482D01*
G01D02*
G03X403175Y241500I2370J2370D01*
G01D02*
X418698D01*
G01X399092Y244585D02*
G02X401562Y243562I0J-3493D01*
G01D02*
X401723Y243401D01*
G01D02*
G03X403174Y242800I1451J1451D01*
G01D02*
X418697D01*
G01X415351Y260010D02*
G02X410500Y258000I-4852J4851D01*
G01X410501Y256700D02*
G03X416267Y259087I-1J8161D01*
G01X411000Y268800D02*
G03X416909Y271247I1J8356D01*
G01X417830Y270329D02*
G02X411000Y267499I-6830J6827D01*
G01D02*
Y267500D01*
G01X422119Y254202D02*
X421271Y253354D01*
G01D02*
G02X420327Y253039I-779J763D01*
G01D02*
G03X419383Y252725I-166J-1077D01*
G01D02*
X418534Y251876D01*
G01D02*
G02X414001Y250000I-4530J4533D01*
G01X414002Y251300D02*
G03X417614Y252796I0J5108D01*
G01D02*
X437409Y272591D01*
G01X418698Y241500D02*
G03X422800Y243199I-1J5803D01*
G01D02*
X444800Y265199D01*
G01X418697Y242800D02*
G03X421881Y244119I0J4503D01*
G01D02*
X443881Y266119D01*
G01X433920Y278578D02*
X415421Y260079D01*
G01D02*
X415351Y260010D01*
G01X416267Y259087D02*
X416334Y259153D01*
G01D02*
X434840Y277659D01*
G01X434115Y267457D02*
X426963Y260305D01*
G01D02*
G03X426648Y259361I762J-779D01*
G01D02*
G02X426333Y258417I-1077J-165D01*
G01D02*
X425485Y257568D01*
G01D02*
G02X424541Y257254I-778J763D01*
G01D02*
G03X423597Y256939I-165J-1078D01*
G01D02*
X422748Y256090D01*
G01D02*
G03X422434Y255146I763J-778D01*
G01D02*
G02X422119Y254202I-1078J-165D01*
G01X416909Y271247D02*
X417080Y271419D01*
G01D02*
X432081Y286420D01*
G01X433000Y285500D02*
X418002Y270502D01*
G01D02*
X417830Y270329D01*
G01X437480Y270822D02*
G03X437166Y269878I763J-778D01*
G01D02*
G02X436851Y268934I-1078J-165D01*
G01D02*
X436003Y268086D01*
G01D02*
G02X435059Y267771I-779J763D01*
G01D02*
G03X434115Y267457I-166J-1077D01*
G01X444800Y265199D02*
G02X447697Y266399I2897J-2897D01*
G01X443881Y266119D02*
G02X447696Y267699I3816J-3817D01*
G01X473659Y281300D02*
X440493D01*
G01D02*
G03X433920Y278578I-2J-9293D01*
G01X434840Y277659D02*
G02X440492Y280000I5652J-5652D01*
G01D02*
X473658D01*
G01X476007Y273100D02*
X441777D01*
G01D02*
G03X438329Y271671I0J-4875D01*
G01D02*
X437480Y270822D01*
G01X437409Y272591D02*
G02X441776Y274400I4367J-4367D01*
G01D02*
X476006D01*
G01X432081Y286420D02*
G02X435896Y288000I3816J-3817D01*
G01X435897Y286700D02*
G03X433000Y285500I0J-4097D01*
G01X435896Y288000D02*
X471160D01*
G01X471161Y286700D02*
X435897D01*
G01X447697Y266399D02*
X478838D01*
G01X447696Y267699D02*
X478837D01*
G01X478762Y284522D02*
X476870Y282630D01*
G01D02*
G02X473659Y281300I-3211J3211D01*
G01X473658Y280000D02*
G03X477789Y281710I2J5841D01*
G01X480527Y274972D02*
G02X476007Y273100I-4521J4522D01*
G01X476006Y274400D02*
G03X479608Y275892I0J5094D01*
G01X471160Y288000D02*
G03X473447Y288948I-1J3235D01*
G01D02*
X475682Y291181D01*
G01D02*
G02X483210Y294300I7529J-7528D01*
G01X483211Y293000D02*
G03X476602Y290261I1J-9346D01*
G01D02*
X474366Y288028D01*
G01D02*
G02X471161Y286700I-3206J3207D01*
G01X471150Y619651D02*
X531650Y559151D01*
G01X470230Y618731D02*
X530730Y558231D01*
G01X464269Y622500D02*
G02X471150Y619651I1J-9731D01*
G01X464269Y621200D02*
G02X470230Y618731I0J-8430D01*
G01X468319Y628200D02*
G02X472830Y626331I-1J-6381D01*
G01D02*
X537580Y561581D01*
G01X468319Y629500D02*
G02X473750Y627251I0J-7682D01*
G01D02*
X538500Y562501D01*
G01X475580Y633080D02*
X502580Y606080D01*
G01X475639Y643100D02*
G02X479500Y641500I-2J-5463D01*
G01X475638Y641800D02*
G02X478580Y640581I-1J-4163D01*
G01X471106Y634934D02*
G02X475581Y633080I0J-6327D01*
G01D02*
X475580D01*
G01X471106Y636234D02*
G02X476501Y634000I2J-7627D01*
G01D02*
X476764Y633736D01*
G01D02*
X546000Y564500D01*
G01X476200Y649800D02*
G02X483883Y646617I-1J-10866D01*
G01X482963Y645697D02*
G03X476200Y648500I-6765J-6762D01*
G01X478838Y266399D02*
G03X483266Y268233I-1J6264D01*
G01D02*
X484516Y269483D01*
G01D02*
G02X486730Y270400I2214J-2214D01*
G01X478837Y267699D02*
G03X482347Y269153I0J4964D01*
G01D02*
X483596Y270402D01*
G01X498628Y285100D02*
X480157D01*
G01D02*
G03X478762Y284522I0J-1972D01*
G01X477789Y281710D02*
X479682Y283603D01*
G01D02*
G02X480157Y283800I475J-474D01*
G01D02*
X498629D01*
G01X502930Y277100D02*
X482945D01*
G01D02*
G03X482449Y276894I1J-702D01*
G01D02*
X480527Y274972D01*
G01X479608Y275892D02*
X481529Y277813D01*
G01D02*
G02X482944Y278400I1416J-1415D01*
G01D02*
X502930D01*
G01X486730Y270400D02*
X495141D01*
G01X483596Y270402D02*
G02X486730Y271700I3133J-3133D01*
G01D02*
X509499D01*
G01X483210Y294300D02*
X498257D01*
G01Y293000D02*
X483211D01*
G01X494900Y351800D02*
G03X493705Y351305I0J-1690D01*
G01D02*
X493600Y351200D01*
G01D02*
G02X492151Y350600I-1449J1449D01*
G01D02*
X489526D01*
G01D02*
G03X487599Y349802I0J-2725D01*
G01X483662D02*
G02X488727Y351900I5065J-5065D01*
G01D02*
X492152D01*
G01D02*
G03X492680Y352120I-2J748D01*
G01D02*
X492785Y352225D01*
G01X498187Y346165D02*
X488323D01*
G01D02*
G03X487599Y345865I0J-1024D01*
G01X483662D02*
X484648Y346851D01*
G01D02*
G02X486130Y347465I1482J-1482D01*
G01D02*
X498187D01*
G01X487599Y341928D02*
G03X487886Y342047I0J406D01*
G01D02*
X488919Y343080D01*
G01D02*
G02X490529Y343747I1610J-1610D01*
G01D02*
X496000D01*
G01X496001Y345047D02*
X490528D01*
G01D02*
G03X487999Y344000I0J-3578D01*
G01D02*
X487852Y343853D01*
G01D02*
G02X487000Y343500I-852J852D01*
G01D02*
G03X483985Y342251I0J-4264D01*
G01D02*
X483662Y341928D01*
G01X498750Y336250D02*
G03X491408Y339291I-7342J-7342D01*
G01D02*
X489352D01*
G01D02*
G03X488365Y339700I-987J-987D01*
G01D02*
X486783D01*
G01D02*
G03X486300Y339500I0J-683D01*
G01D02*
X485590Y338789D01*
G01D02*
G02X483662Y337991I-1927J1928D01*
G01X487599D02*
X491408D01*
G01D02*
G02X497830Y335331I0J-9082D01*
G01X492785Y352225D02*
G02X494900Y353100I2114J-2115D01*
G01X479500Y641500D02*
X553249Y567751D01*
G01X478580Y640580D02*
X511580Y607580D01*
G01X478580Y640581D02*
Y640580D01*
G01X483883Y646617D02*
X485600Y644901D01*
G01D02*
X561387Y569114D01*
G01X559330Y569331D02*
X484064Y644598D01*
G01D02*
X482963Y645697D01*
G01X486131Y654392D02*
X566511Y574012D01*
G01X565590Y573092D02*
X486591Y652092D01*
G01X481000Y656517D02*
G02X486131Y654392I0J-7257D01*
G01X486591Y652092D02*
X485211Y653472D01*
G01D02*
G03X481001Y655217I-4212J-4211D01*
G01X574500Y575500D02*
X488828Y661172D01*
G01D02*
G03X482000Y664000I-6828J-6829D01*
G01X481999Y662700D02*
G02X487908Y660252I0J-8356D01*
G01D02*
X573580Y574580D01*
G01X485593Y669500D02*
G02X490831Y667330I0J-7406D01*
G01D02*
X490830D01*
G01D02*
X580459Y577701D01*
G01X581379Y578621D02*
X491750Y668250D01*
G01D02*
G03X485594Y670800I-6156J-6156D01*
G01X495141Y270400D02*
G02X496031Y269955I11J-1090D01*
G01D02*
G03X496921Y269510I879J645D01*
G01D02*
X498121D01*
G01D02*
G03X499011Y269955I11J1090D01*
G01D02*
G02X499901Y270400I879J-645D01*
G01X504830Y287669D02*
G02X498628Y285100I-6202J6202D01*
G01X498629Y283800D02*
G03X505749Y286749I-1J10071D01*
G01X515154Y285815D02*
X508920Y279581D01*
G01D02*
G02X502930Y277100I-5989J5989D01*
G01Y278400D02*
G03X508000Y280500I0J7170D01*
G01D02*
X527500Y300000D01*
G01X499901Y270400D02*
X509500D01*
G01D02*
G03X521951Y275558I-1J17609D01*
G01X509499Y271700D02*
G03X521031Y276478I-1J16308D01*
G01X521830Y304669D02*
X504830Y287669D01*
G01X505749Y286749D02*
X523227Y304227D01*
G01X498257Y294300D02*
G03X504580Y296920I-1J8942D01*
G01D02*
X515458Y307798D01*
G01X516378Y306878D02*
X505500Y296000D01*
G01D02*
G02X498257Y293000I-7243J7243D01*
G01X499330Y342330D02*
X506955Y334705D01*
G01D02*
X509581Y332080D01*
G01D02*
G03X512913Y330700I3333J3334D01*
G01X510500Y333000D02*
X507800Y335700D01*
G01D02*
X507799D01*
G01D02*
X500243Y343256D01*
G01X539443Y329300D02*
X506984D01*
G01D02*
G02X504792Y330208I0J3100D01*
G01D02*
X498750Y336250D01*
G01X497830Y335331D02*
X503873Y329288D01*
G01D02*
G03X506983Y328000I3111J3112D01*
G01D02*
X539444D01*
G01X515000Y340000D02*
X510111Y344888D01*
G01D02*
G03X508393Y345600I-1718J-1717D01*
G01D02*
X507435D01*
G01D02*
G02X505076Y346577I-1J3335D01*
G01D02*
X503351Y348301D01*
G01D02*
X501687Y349965D01*
G01D02*
G03X497257Y351800I-4430J-4430D01*
G01D02*
X494900D01*
G01X497258Y353100D02*
G02X502607Y350885I0J-7566D01*
G01D02*
X505996Y347496D01*
G01D02*
G03X507435Y346900I1439J1439D01*
G01D02*
X508394D01*
G01D02*
G02X511031Y345808I0J-3730D01*
G01X513975Y334500D02*
G02X509750Y336250I1J5977D01*
G01D02*
X501000Y345000D01*
G01D02*
G03X498187Y346165I-2813J-2813D01*
G01Y347465D02*
G02X501920Y345919I1J-5278D01*
G01D02*
X510669Y337170D01*
G01X496000Y343747D02*
G02X499265Y342394I-1J-4618D01*
G01D02*
X499330Y342330D01*
G01X500243Y343256D02*
X500181Y343317D01*
G01D02*
G03X496001Y345047I-4181J-4188D01*
G01X494900Y353100D02*
X497258D01*
G01X509700Y490612D02*
Y384099D01*
G01D02*
G03X511565Y379595I6371J0D01*
G01X512830Y498170D02*
G03X509700Y490612I7560J-7558D01*
G01X505800Y602861D02*
X545080Y563581D01*
G01X502580Y606080D02*
X505800Y602861D01*
G01X517891Y287293D02*
X517042Y286445D01*
G01D02*
G02X516098Y286130I-779J762D01*
G01D02*
G03X515154Y285815I-165J-1077D01*
G01X521951Y275558D02*
X528594Y282201D01*
G01X521031Y276478D02*
X538277Y293722D01*
G01X528422Y299083D02*
X526949Y297610D01*
G01D02*
G03X526634Y296666I762J-779D01*
G01D02*
G02X526319Y295722I-1077J-165D01*
G01D02*
X525471Y294873D01*
G01D02*
G02X524527Y294559I-778J763D01*
G01D02*
G03X523583Y294244I-165J-1078D01*
G01D02*
X522734Y293395D01*
G01D02*
G03X522420Y292451I763J-778D01*
G01D02*
G02X522105Y291507I-1078J-165D01*
G01D02*
X521257Y290659D01*
G01D02*
G02X520313Y290344I-779J763D01*
G01D02*
G03X519369Y290030I-166J-1077D01*
G01D02*
X518520Y289181D01*
G01D02*
G03X518205Y288237I763J-779D01*
G01D02*
G02X517891Y287293I-1077J-166D01*
G01X523348Y319359D02*
X524113Y318593D01*
G01D02*
G02X524525Y317600I-993J-994D01*
G01D02*
Y310499D01*
G01D02*
G02X522307Y305147I-7571J2D01*
G01D02*
X521830Y304670D01*
G01D02*
Y304669D01*
G01X523227Y304227D02*
G03X525825Y310500I-6274J6273D01*
G01D02*
Y317600D01*
G01D02*
G02X526237Y318593I1405J-1D01*
G01D02*
X527002Y319359D01*
G01X515458Y307798D02*
G03X517200Y312001I-4200J4203D01*
G01D02*
G03X516734Y313126I-1591J0D01*
G01D02*
X515860Y314000D01*
G01X519706D02*
X519061Y313356D01*
G01D02*
G03X518500Y312000I1356J-1355D01*
G01D02*
G02X516378Y306878I-7243J0D01*
G01X530812Y334500D02*
X513975D01*
G01X512913Y330700D02*
X535337D01*
G01X535336Y332000D02*
X512914D01*
G01D02*
G02X510500Y333000I0J3414D01*
G01X527328Y343798D02*
X526500Y342969D01*
G01X526989Y346043D02*
X526500Y346532D01*
G01X528756Y350400D02*
X522400D01*
G01D02*
G02X521035Y350966I1J1931D01*
G01D02*
X520500Y351500D01*
G01X528756Y349100D02*
X522400D01*
G01D02*
G03X521142Y348579I0J-1779D01*
G01D02*
X520500Y347937D01*
G01X529900Y338000D02*
X519829D01*
G01D02*
G02X515000Y340000I1J6831D01*
G01X511031Y345808D02*
X515919Y340920D01*
G01D02*
G03X519830Y339300I3911J3911D01*
G01D02*
X529901D01*
G01X510669Y337170D02*
G03X513976Y335800I3307J3307D01*
G01D02*
X530813D01*
G01X512485Y380515D02*
X525600Y367400D01*
G01D02*
G02X526500Y365227I-2175J-2174D01*
G01D02*
Y363134D01*
G01D02*
G02X525699Y361199I-2734J-1D01*
G01D02*
X525400Y360900D01*
G01D02*
G02X523466Y360099I-1934J1933D01*
G01D02*
X522300D01*
G01D02*
G03X521211Y359648I0J-1540D01*
G01D02*
X520500Y358937D01*
G01X511565Y379595D02*
X524680Y366481D01*
G01D02*
G02X525200Y365226I-1255J-1255D01*
G01D02*
Y363133D01*
G01D02*
G02X524780Y362119I-1434J0D01*
G01D02*
X524480Y361819D01*
G01D02*
G02X523466Y361399I-1014J1014D01*
G01D02*
X522300D01*
G01D02*
G02X521106Y361893I-1J1688D01*
G01D02*
X520500Y362500D01*
G01X526972Y356060D02*
X526500Y356532D01*
G01X528000Y354500D02*
G03X526500Y352969I466J-1957D01*
G01X511000Y490611D02*
Y384100D01*
G01D02*
G03X512485Y380515I5070J0D01*
G01X516700Y487499D02*
Y383099D01*
G01D02*
G03X518918Y377742I7578J0D01*
G01D02*
X519530Y377130D01*
G01D02*
X527480Y369181D01*
G01X518000Y487500D02*
Y383100D01*
G01D02*
G03X519838Y378662I6277J0D01*
G01D02*
X528400Y370100D01*
G01X523434Y485945D02*
Y380699D01*
G01D02*
G03X525177Y376484I5969J1D01*
G01D02*
X531230Y370431D01*
G01X524734Y485944D02*
Y380700D01*
G01D02*
G03X526102Y377399I4669J1D01*
G01D02*
X526150Y377350D01*
G01D02*
X532149Y371351D01*
G01X531500Y515000D02*
X513750Y497250D01*
G01D02*
G03X511000Y490611I6639J-6639D01*
G01X521705Y507045D02*
X512830Y498170D01*
G01X536330Y510669D02*
X520305Y494644D01*
G01D02*
X519752Y494093D01*
G01D02*
X519201Y493542D01*
G01D02*
G03X516700Y487499I6043J-6040D01*
G01X537248Y509748D02*
X521224Y493724D01*
G01D02*
X520121Y492622D01*
G01D02*
G03X518000Y487500I5122J-5121D01*
G01X534830Y499670D02*
X525080Y489920D01*
G01D02*
G03X523434Y485945I3977J-3975D01*
G01X545500Y508500D02*
X526000Y489000D01*
G01D02*
G03X524734Y485944I3056J-3056D01*
G01X530580Y515919D02*
X521705Y507045D01*
G01X512500Y606661D02*
X552330Y566831D01*
G01X511580Y607580D02*
X512500Y606661D01*
G01X528594Y282201D02*
G02X529538Y282515I778J-763D01*
G01D02*
G03X530482Y282830I165J1078D01*
G01D02*
X531331Y283679D01*
G01D02*
G03X531646Y284623I-763J779D01*
G01D02*
G02X531960Y285567I1077J166D01*
G01D02*
X532809Y286415D01*
G01D02*
G02X533753Y286730I779J-763D01*
G01X532000Y307499D02*
G02X528580Y299242I-11681J1D01*
G01D02*
X528422Y299083D01*
G01X527500Y300000D02*
X527659Y300160D01*
G01D02*
G03X530700Y307500I-7340J7341D01*
G01X533753Y286730D02*
G03X534697Y287044I166J1077D01*
G01D02*
X535545Y287893D01*
G01D02*
G03X535860Y288837I-762J779D01*
G01D02*
G02X536175Y289781I1077J165D01*
G01D02*
X544769Y298375D01*
G01X538277Y293722D02*
X543850Y299295D01*
G01X532000Y323793D02*
Y307499D01*
G01X530700Y307500D02*
Y323443D01*
G01X543575Y309927D02*
G03X540500Y311200I-3074J-3075D01*
G01D02*
X540424D01*
G01D02*
G02X539700Y311500I0J1024D01*
G01D02*
X538150Y313050D01*
G01D02*
G02X537437Y314771I1721J1721D01*
G01D02*
Y319000D01*
G01D02*
G02X538019Y320405I1987J0D01*
G01X543530Y308130D02*
X543080Y308581D01*
G01D02*
X542707Y308955D01*
G01D02*
X542706D01*
G01D02*
X542702Y308959D01*
G01D02*
X542651Y309011D01*
G01D02*
G03X540500Y309900I-2152J-2159D01*
G01D02*
X540423D01*
G01D02*
G02X538780Y310580I0J2325D01*
G01D02*
X537229Y312131D01*
G01D02*
X537230D01*
G01D02*
G02X536137Y314770I2641J2640D01*
G01D02*
Y319000D01*
G01D02*
G03X535555Y320405I-1987J0D01*
G01X533502Y325500D02*
G03X532645Y325145I0J-1212D01*
G01D02*
X532500Y325000D01*
G01D02*
G03X532000Y323793I1207J-1207D01*
G01X530700Y323443D02*
G03X530699Y323482I-2908J-55D01*
G01D02*
G03X529848Y325500I-2909J-38D01*
G01X538019Y320405D02*
X538614Y321000D01*
G01X535555Y320405D02*
X534960Y321000D01*
G01X535124Y336285D02*
G02X530812Y334500I-4311J4312D01*
G01X535337Y330700D02*
G03X538845Y332153I-1J4963D01*
G01D02*
X544555Y337863D01*
G01X543255Y338402D02*
X537926Y333073D01*
G01D02*
G02X535336Y332000I-2590J2590D01*
G01X543917Y331153D02*
G02X539443Y329300I-4474J4474D01*
G01X539444Y328000D02*
G03X544837Y330234I0J7627D01*
G01X537300Y369008D02*
Y350217D01*
G01D02*
G02X536299Y347799I-3417J-2D01*
G01D02*
X533988Y345488D01*
G01D02*
X533989D01*
G01D02*
X533972Y345471D01*
G01D02*
G02X530899Y344200I-3071J3074D01*
G01D02*
X528300D01*
G01D02*
G03X527328Y343798I-1J-1374D01*
G01X536000Y369007D02*
Y350216D01*
G01D02*
X535999Y350217D01*
G01D02*
G02X535380Y348719I-2117J-2D01*
G01D02*
X533052Y346391D01*
G01D02*
G02X530900Y345500I-2152J2153D01*
G01D02*
X528300D01*
G01D02*
G02X526989Y346043I0J1854D01*
G01X531730Y352569D02*
X530130Y350969D01*
G01D02*
G02X528756Y350400I-1374J1374D01*
G01X533500Y353704D02*
G02X532649Y351649I-2905J-1D01*
G01D02*
X531050Y350050D01*
G01D02*
G02X528756Y349100I-2293J2293D01*
G01X541300Y371679D02*
Y350475D01*
G01D02*
G02X539169Y345330I-7276J0D01*
G01D02*
X533208Y339369D01*
G01D02*
G02X529900Y338000I-3306J3308D01*
G01X529901Y339300D02*
G03X532289Y340289I0J3377D01*
G01D02*
X538250Y346250D01*
G01D02*
G03X539999Y350475I-4227J4224D01*
G01D02*
X540000Y350474D01*
G01D02*
Y371678D01*
G01X545217Y352500D02*
G02X540888Y342049I-14780J0D01*
G01D02*
X535124Y336285D01*
G01X530813Y335800D02*
G03X534205Y337205I0J4797D01*
G01D02*
X538999Y341999D01*
G01D02*
Y342000D01*
G01D02*
X539968Y342969D01*
G01D02*
G03X543917Y352501I-9530J9532D01*
G01X544176Y339324D02*
X543255Y338403D01*
G01D02*
Y338402D01*
G01X527480Y369181D02*
G02X528700Y366236I-2945J-2945D01*
G01D02*
Y356779D01*
G01D02*
G02X528530Y356369I-580J0D01*
G01D02*
X528216Y356055D01*
G01D02*
G02X527600Y355800I-616J617D01*
G01D02*
G02X526972Y356060I0J888D01*
G01X528400Y370100D02*
G02X530000Y366237I-3865J-3864D01*
G01D02*
Y356778D01*
G01D02*
G02X529449Y355449I-1880J1D01*
G01D02*
X529149Y355149D01*
G01D02*
X529150D01*
G01D02*
X529136Y355135D01*
G01D02*
G02X528000Y354500I-1690J1690D01*
G01X531230Y370431D02*
G02X532200Y368089I-2342J-2342D01*
G01D02*
Y353704D01*
G01D02*
G02X531730Y352569I-1605J0D01*
G01X532149Y371351D02*
G02X533500Y368089I-3261J-3261D01*
G01D02*
Y353704D01*
G01X531500Y483235D02*
Y378626D01*
G01D02*
G03X532650Y375850I3926J0D01*
G01D02*
X535750Y372750D01*
G01D02*
G02X537300Y369008I-3742J-3742D01*
G01X530200Y483234D02*
Y378625D01*
G01D02*
G03X531730Y374931I5226J1D01*
G01D02*
Y374930D01*
G01D02*
X534830Y371830D01*
G01D02*
G02X536000Y369007I-2822J-2823D01*
G01X538300Y480105D02*
Y378921D01*
G01D02*
G03X539800Y375300I5121J0D01*
G01D02*
G02X541300Y371679I-3621J-3621D01*
G01X540000Y371678D02*
G03X538880Y374380I-3820J0D01*
G01D02*
G02X537000Y378920I4542J4540D01*
G01D02*
Y480104D01*
G01X532748Y486248D02*
G03X531500Y483235I3013J-3013D01*
G01X531828Y487168D02*
G03X530200Y483234I3934J-3932D01*
G01X558850Y502349D02*
X539499Y482998D01*
G01D02*
G03X538301Y480104I2895J-2893D01*
G01D02*
X538300Y480105D01*
G01X537000Y480104D02*
G02X538579Y483918I5393J1D01*
G01X552858Y506358D02*
X532748Y486248D01*
G01X551939Y507278D02*
X532330Y487669D01*
G01D02*
Y487670D01*
G01D02*
X531828Y487168D01*
G01X544580Y509419D02*
X534830Y499670D01*
G01X538579Y483918D02*
X558496Y503834D01*
G01X534000Y521036D02*
G02X531500Y515000I-8538J1D01*
G01X532700Y521037D02*
G02X530580Y515919I-7238J0D01*
G01X539700Y518500D02*
G02X536546Y510884I-10770J-1D01*
G01D02*
X536330Y510669D01*
G01X541001Y518500D02*
G02X537465Y509963I-12071J-1D01*
G01D02*
X537248Y509748D01*
G01X534000Y553476D02*
Y521036D01*
G01X532700Y553475D02*
Y521037D01*
G01X539700Y556463D02*
Y518500D01*
G01X541000Y556464D02*
Y518500D01*
G01D02*
X541001D01*
G01X531650Y559151D02*
Y559150D01*
G01D02*
G02X534000Y553476I-5676J-5675D01*
G01X530730Y558231D02*
G02X532700Y553475I-4756J-4756D01*
G01X537580Y561581D02*
G02X539700Y556463I-5118J-5118D01*
G01X538500Y562501D02*
Y562500D01*
G01D02*
G02X541000Y556464I-6038J-6037D01*
G01X544769Y298375D02*
G03X545700Y300623I-2248J2248D01*
G01D02*
Y306032D01*
G01X543850Y299295D02*
G03X544399Y300623I-1330J1327D01*
G01D02*
X544400Y300622D01*
G01D02*
Y306033D01*
G01X545700Y306032D02*
G03X544450Y309050I-4268J0D01*
G01D02*
X544000Y309500D01*
G01D02*
X543627Y309874D01*
G01D02*
X543575Y309927D01*
G01X544400Y306033D02*
X544399Y306032D01*
G01D02*
G03X543530Y308130I-2967J0D01*
G01X552852Y340088D02*
X543917Y331153D01*
G01X544837Y330234D02*
X553051Y338448D01*
G01X544555Y337863D02*
Y337864D01*
G01D02*
X545096Y338405D01*
G01D02*
G03X552000Y355073I-16670J16669D01*
G01X550700Y355074D02*
G02X544176Y339324I-22274J0D01*
G01X558200Y353000D02*
G02X552852Y340088I-18261J0D01*
G01X553051Y338448D02*
X553052D01*
G01D02*
X553772Y339168D01*
G01D02*
G03X559500Y353001I-13834J13831D01*
G01X545217Y476403D02*
Y352500D01*
G01X543917Y352501D02*
Y476404D01*
G01X552000Y355073D02*
Y473500D01*
G01X550700Y473499D02*
Y355074D01*
G01X558200Y471999D02*
Y353000D01*
G01X559500Y353001D02*
Y472000D01*
G01X566500Y499500D02*
X546500Y479500D01*
G01D02*
G03X545217Y476403I3097J-3097D01*
G01X543917Y476404D02*
G02X545580Y480419I5680J-1D01*
G01D02*
X565580Y500419D01*
G01X552000Y473500D02*
G02X553414Y476914I4828J0D01*
G01D02*
X573500Y497000D01*
G01X572580Y497919D02*
X552496Y477835D01*
G01D02*
G03X550700Y473499I4336J-4336D01*
G01X579080Y494419D02*
X559580Y474919D01*
G01D02*
Y474920D01*
G01D02*
X559287Y474627D01*
G01D02*
G03X558200Y471999I2628J-2626D01*
G01X559500Y472000D02*
G02X560207Y473707I2414J0D01*
G01X555500Y562316D02*
Y512737D01*
G01D02*
G02X552858Y506358I-9020J-1D01*
G01X554200Y562316D02*
Y512737D01*
G01D02*
G02X551939Y507278I-7720J0D01*
G01X546700Y559670D02*
Y514537D01*
G01D02*
G02X544580Y509419I-7238J0D01*
G01X548000Y559671D02*
Y514536D01*
G01D02*
G02X545500Y508500I-8538J1D01*
G01X562500Y510412D02*
G02X559380Y502878I-10654J-1D01*
G01D02*
X558850Y502349D01*
G01X558496Y503834D02*
G03X561199Y510412I-6651J6577D01*
G01X553249Y567751D02*
G02X555500Y562316I-5434J-5434D01*
G01X552330Y566831D02*
G02X554200Y562316I-4515J-4515D01*
G01X545080Y563581D02*
G02X546700Y559670I-3911J-3911D01*
G01X546000Y564500D02*
G02X548000Y559671I-4831J-4830D01*
G01X560468Y568184D02*
X559314Y569338D01*
G01D02*
X559318Y569342D01*
G01D02*
X559330Y569331D01*
G01X560207Y473707D02*
X580000Y493500D01*
G01X569500Y506743D02*
G02X566500Y499500I-10245J1D01*
G01X573500Y497000D02*
G03X576500Y504243I-7245J7244D01*
G01X575200Y504244D02*
G02X572580Y497919I-8945J0D01*
G01X562500Y566427D02*
Y510412D01*
G01X561199D02*
X561200Y510411D01*
G01D02*
Y566416D01*
G01X569500Y566796D02*
Y506743D01*
G01X565580Y500419D02*
G03X568200Y506744I-6325J6325D01*
G01D02*
Y566795D01*
G01X575200Y570671D02*
Y504244D01*
G01X561387Y569114D02*
G02X561395Y569105I-2831J-2525D01*
G01D02*
G02X562500Y566427I-2695J-2679D01*
G01X561200Y566416D02*
G03X560468Y568184I-2500J0D01*
G01X566511Y574012D02*
G02X569500Y566796I-7216J-7216D01*
G01X568200Y566795D02*
G03X565591Y573093I-8905J0D01*
G01D02*
X565590Y573092D01*
G01X576500Y570672D02*
G03X574500Y575500I-6828J0D01*
G01X573580Y574580D02*
Y574581D01*
G01D02*
G02X575200Y570671I-3908J-3910D01*
G01X582200Y501951D02*
G02X579080Y494419I-10652J0D01*
G01X580000Y493500D02*
G03X583500Y501950I-8452J8451D01*
G01X576500Y504243D02*
Y570672D01*
G01X582200Y573499D02*
Y501951D01*
G01X583500Y501950D02*
Y573500D01*
G01X580459Y577701D02*
G02X582200Y573499I-4201J-4202D01*
G01X583500Y573500D02*
G03X581379Y578621I-7243J0D01*
G01X1150000Y760340D02*
Y744261D01*
G01D02*
X1151511Y742750D01*
G01X1152570Y762910D02*
X1150000Y760340D01*
G01X1167682Y728182D02*
X1167000Y727500D01*
G01X1151511Y742750D02*
X1153138D01*
G01D02*
X1155389Y740499D01*
G01D02*
X1155460D01*
G01D02*
X1157000Y738959D01*
G01D02*
Y734500D01*
G01X1151300Y759801D02*
Y744800D01*
G01D02*
X1152050Y744050D01*
G01D02*
X1153677D01*
G01D02*
X1155928Y741799D01*
G01D02*
X1155999D01*
G01D02*
X1158300Y739498D01*
G01D02*
Y736184D01*
G01D02*
X1158600Y735884D01*
G01D02*
Y733190D01*
G01D02*
X1157112Y731702D01*
G01X1153870Y767087D02*
Y762371D01*
G01D02*
X1151300Y759801D01*
G01X1165200Y762661D02*
Y761139D01*
G01D02*
X1165600Y760739D01*
G01D02*
X1168639D01*
G01Y755739D02*
X1166578D01*
G01D02*
X1166033Y755194D01*
G01D02*
Y753806D01*
G01D02*
X1166500Y753339D01*
G01D02*
X1168639D01*
G01X1163900Y763200D02*
Y760600D01*
G01D02*
X1165061Y759439D01*
G01D02*
X1168100D01*
G01Y757039D02*
X1166039D01*
G01D02*
X1164733Y755733D01*
G01D02*
Y753267D01*
G01D02*
X1165961Y752039D01*
G01D02*
X1168100D01*
G01X1155919Y784317D02*
Y778010D01*
G01D02*
X1154550Y776641D01*
G01D02*
Y771808D01*
G01D02*
X1154100Y771358D01*
G01D02*
Y769156D01*
G01D02*
X1152570Y767626D01*
G01D02*
Y762910D01*
G01X1157219Y783778D02*
Y777471D01*
G01D02*
X1155850Y776102D01*
G01D02*
Y771269D01*
G01D02*
X1155400Y770819D01*
G01D02*
Y768617D01*
G01D02*
X1153870Y767087D01*
G01X1164000Y779465D02*
Y777854D01*
G01D02*
X1165357Y776496D01*
G01D02*
Y774782D01*
G01D02*
X1165803Y774336D01*
G01D02*
X1167518D01*
G01X1168839Y763139D02*
X1165678D01*
G01D02*
X1165200Y762661D01*
G01X1162700Y779465D02*
Y777315D01*
G01D02*
X1164057Y775958D01*
G01D02*
Y774243D01*
G01D02*
X1165264Y773036D01*
G01D02*
X1166979D01*
G01D02*
X1170000Y770015D01*
G01X1168300Y764439D02*
X1165139D01*
G01D02*
X1163900Y763200D01*
G01X1154200Y788900D02*
X1155092Y788008D01*
G01D02*
Y785146D01*
G01D02*
X1155100Y785136D01*
G01D02*
X1155919Y784317D01*
G01X1154712Y792690D02*
X1156000D01*
G01D02*
X1156392Y792298D01*
G01D02*
Y791300D01*
G01D02*
X1155700Y790608D01*
G01D02*
Y790100D01*
G01D02*
X1156392Y789408D01*
G01D02*
Y785683D01*
G01D02*
X1157220Y784855D01*
G01D02*
Y783779D01*
G01D02*
X1157219Y783778D01*
G01X1165492Y780957D02*
X1164000Y779465D01*
G01X1162693Y780865D02*
Y779472D01*
G01D02*
X1162700Y779465D01*
G01X1169000Y729990D02*
X1169282Y729708D01*
G01X1167682Y730814D02*
Y728182D01*
G01X1169800Y752178D02*
Y736043D01*
G01D02*
X1169420Y735662D01*
G01D02*
X1169000Y735242D01*
G01D02*
Y729990D01*
G01X1168500Y751639D02*
Y736581D01*
G01D02*
X1167700Y735781D01*
G01D02*
Y730832D01*
G01D02*
X1167682Y730814D01*
G01X1168639Y760739D02*
X1169800Y759578D01*
G01D02*
Y756900D01*
G01D02*
X1168639Y755739D01*
G01Y753339D02*
X1169800Y752178D01*
G01X1168100Y759439D02*
X1168500Y759039D01*
G01D02*
Y757439D01*
G01D02*
X1168100Y757039D01*
G01Y752039D02*
X1168500Y751639D01*
G01X1167518Y774336D02*
X1171300Y770554D01*
G01D02*
Y765600D01*
G01D02*
X1168839Y763139D01*
G01X1170000Y770015D02*
Y766139D01*
G01D02*
X1168300Y764439D01*
G54D11*
G01X560155Y309100D02*
G03X559558Y310541I-2038J0D01*
G01D02*
X556941Y313158D01*
G01D02*
G02X556055Y315299I2145J2141D01*
G01D02*
Y316000D01*
G01D02*
G02X561555Y321500I5500J0D01*
G01X560336Y311319D02*
X557855Y313800D01*
G01D02*
X557721Y313935D01*
G01D02*
G02X557155Y315300I1365J1366D01*
G01D02*
Y316000D01*
G01D02*
G02X561555Y320400I4400J0D01*
G01X552954Y315945D02*
X554228Y314671D01*
G01D02*
G02X554724Y313496I-1197J-1198D01*
G01D02*
Y313093D01*
G01D02*
G02X553385Y311607I-1494J0D01*
G01D02*
G02X553231Y311600I-145J1486D01*
G01D02*
X552731D01*
G01D02*
G02X551577Y312078I0J1631D01*
G01D02*
X550050Y313605D01*
G01D02*
G02X549555Y314800I1195J1195D01*
G01D02*
Y321000D01*
G01X556889Y308070D02*
Y308411D01*
G01D02*
G03X554800Y310500I-2089J0D01*
G01D02*
X552730D01*
G01D02*
G02X550799Y311300I0J2731D01*
G01D02*
X549272Y312827D01*
G01D02*
G02X548455Y314799I1973J1973D01*
G01D02*
Y321000D01*
G01X549555D02*
G02X550301Y322801I2547J0D01*
G01D02*
X552323Y324823D01*
G01D02*
G02X553957Y325500I1634J-1634D01*
G01D02*
X564733D01*
G01X548455Y321000D02*
G02X549523Y323579I3648J0D01*
G01D02*
X551545Y325601D01*
G01D02*
G02X553956Y326600I2412J-2412D01*
G01D02*
X564732D01*
G01X576574Y292642D02*
G03X575935Y295212I-5486J0D01*
G01D02*
G02X575655Y296339I2124J1126D01*
G01D02*
Y308233D01*
G01X560829Y290355D02*
G02X560155Y291982I1627J1627D01*
G01D02*
Y309100D01*
G01X564764Y298230D02*
G02X565000Y297660I-570J-570D01*
G01D02*
Y295000D01*
G01D02*
G02X564886Y294725I-389J0D01*
G01D02*
X564559Y294398D01*
G01D02*
X564448Y294288D01*
G01D02*
G02X563450Y293874I-999J998D01*
G01D02*
G02X562455Y294400I355J1876D01*
G01D02*
X561855Y295000D01*
G01D02*
G02X561255Y296449I1449J1449D01*
G01D02*
Y309100D01*
G01X575655Y308233D02*
G02X576905Y311250I4268J-1D01*
G01X561255Y309100D02*
G03X560336Y311319I-3138J0D01*
G01X568699Y315945D02*
X570200Y312946D01*
G01D02*
G03X570871Y312723I447J224D01*
G01D02*
X570872D01*
G01D02*
X571317Y312947D01*
G01D02*
G03X572055Y314726I-1778J1780D01*
G01D02*
Y316501D01*
G01D02*
G02X573194Y319249I3888J-1D01*
G01D02*
X574222Y320278D01*
G01X572639Y308070D02*
X571139Y311067D01*
G01D02*
G02X571362Y311738I447J224D01*
G01D02*
X571363D01*
G01D02*
X571366Y311740D01*
G01D02*
X571811Y311963D01*
G01D02*
X571956Y312036D01*
G01D02*
G03X572096Y312169I-2420J2687D01*
G01D02*
G03X573155Y314725I-2557J2557D01*
G01D02*
Y316500D01*
G01D02*
G02X573972Y318471I2788J-1D01*
G01D02*
X575000Y319500D01*
G01X561555Y321500D02*
X567000D01*
G01D02*
G03X572122Y323621I1J7243D01*
G01D02*
X574379Y325879D01*
G01D02*
G02X579500Y328000I5121J-5122D01*
G01X561555Y320400D02*
X567000D01*
G01D02*
Y320399D01*
G01D02*
G03X572900Y322843I0J8344D01*
G01D02*
X575157Y325101D01*
G01D02*
G02X579500Y326900I4343J-4343D01*
G01X574222Y320278D02*
X576222Y322278D01*
G01X575000Y319500D02*
X577000Y321500D01*
G01X564733Y325500D02*
G03X567750Y326750I-1J4268D01*
G01D02*
X568500Y327500D01*
G01D02*
G02X570673Y328400I2173J-2173D01*
G01D02*
X572499D01*
G01D02*
G03X579254Y331197I1J9552D01*
G01X564732Y326600D02*
G03X566972Y327528I0J3168D01*
G01D02*
X567722Y328278D01*
G01D02*
G02X570673Y329500I2951J-2951D01*
G01D02*
X572500D01*
G01D02*
G03X578476Y331975I0J8452D01*
G01X586679Y274376D02*
X600233Y260822D01*
G01X589555Y288800D02*
X592282Y286073D01*
G01D02*
G02X593065Y284182I-1892J-1891D01*
G01X588777Y288022D02*
X591504Y285295D01*
G01D02*
G02X591965Y284182I-1113J-1113D01*
G01D02*
Y283227D01*
G01D02*
G03X592627Y281628I2261J0D01*
G01D02*
X598710Y275545D01*
G01X580955Y287344D02*
X582877Y285422D01*
G01D02*
G02X583355Y284268I-1153J-1154D01*
G01D02*
Y282400D01*
G01D02*
G03X586679Y274376I11347J0D01*
G01X581733Y288122D02*
X583655Y286200D01*
G01D02*
G02X584455Y284269I-1931J-1931D01*
G01D02*
Y282401D01*
G01D02*
G03X587457Y275154I10247J-1D01*
G01D02*
X601011Y261600D01*
G01X592324Y290355D02*
X592832Y290863D01*
G01Y293168D02*
X592478Y293522D01*
G01D02*
G03X589977I-1250J-1250D01*
G01D02*
X589555Y293100D01*
G01D02*
G03Y288800I2150J-2150D01*
G01X593500Y296000D02*
X592274D01*
G01D02*
G03X589927Y295028I0J-3319D01*
G01D02*
X588777Y293878D01*
G01D02*
G03Y288022I2928J-2928D01*
G01X576574Y290355D02*
Y292642D01*
G01X580514Y298230D02*
G02X579545Y295889I-3310J-1D01*
G01D02*
X579355Y295700D01*
G01D02*
G02X578674Y295418I-681J681D01*
G01D02*
X577655D01*
G01D02*
G02X576909Y295727I0J1055D01*
G01D02*
X576908Y295728D01*
G01D02*
G02X576755Y296340I1151J613D01*
G01D02*
Y308232D01*
G01X584018Y309501D02*
Y298311D01*
G01D02*
G02X583136Y296180I-3013J-1D01*
G01D02*
X580955Y294000D01*
G01D02*
G03Y287344I3328J-3328D01*
G01X585118Y309502D02*
Y298311D01*
G01D02*
G02X583914Y295402I-4113J-1D01*
G01D02*
X581733Y293222D01*
G01D02*
G03Y288122I2550J-2550D01*
G01X576905Y311250D02*
X579355Y313700D01*
G01D02*
G03X579955Y315149I-1449J1449D01*
G01D02*
Y316368D01*
G01D02*
G02X580755Y318300I2732J0D01*
G01D02*
X581955Y319500D01*
G01X576755Y308232D02*
G02X577683Y310472I3168J0D01*
G01D02*
X580133Y312922D01*
G01D02*
G03X581055Y315149I-2227J2226D01*
G01D02*
Y316368D01*
G01D02*
G02X581533Y317522I1632J0D01*
G01D02*
X582733Y318722D01*
G01D02*
G02X584370Y319400I1637J-1637D01*
G01X584449Y315945D02*
X585947Y312947D01*
G01D02*
G02X585723Y312276I-448J-223D01*
G01D02*
X585722D01*
G01D02*
X585700Y312266D01*
G01D02*
X585132Y311983D01*
G01D02*
G03X584018Y309501I2203J-2480D01*
G01X588384Y308070D02*
X586887Y311068D01*
G01D02*
G03X586216Y311292I-447J-223D01*
G01D02*
X586215D01*
G01D02*
X585767Y311069D01*
G01D02*
G03X585118Y309502I1567J-1567D01*
G01X581955Y319500D02*
G02X584370Y320500I2415J-2415D01*
G01D02*
X598197D01*
G01X584370Y319400D02*
X598197D01*
G01X579500Y328000D02*
X582589D01*
G01D02*
G03X585001Y328999I0J3411D01*
G01D02*
X592000Y335998D01*
G01X579500Y326900D02*
X582589D01*
G01D02*
G03X585779Y328221I0J4511D01*
G01D02*
X592779Y335221D01*
G01X576222Y322278D02*
G02X580620Y324100I4399J-4399D01*
G01D02*
X587500D01*
G01D02*
G03X590913Y325514I0J4826D01*
G01D02*
X593627Y328228D01*
G01X577000Y321500D02*
G02X580621Y323000I3621J-3621D01*
G01D02*
X587500D01*
G01D02*
G03X591691Y324736I0J5927D01*
G01D02*
X594405Y327450D01*
G01X579254Y331197D02*
X595325Y347268D01*
G01X578476Y331975D02*
X594547Y348046D01*
G01X592000Y335998D02*
X592381Y336381D01*
G01D02*
G02X597500Y338501I5118J-5118D01*
G01X599810Y276000D02*
X606405Y269405D01*
G01D02*
G03X615712Y265550I9307J9307D01*
G01X598710Y275544D02*
X605627Y268627D01*
G01D02*
G03X615712Y264450I10085J10085D01*
G01X600233Y260822D02*
X604413Y256643D01*
G01D02*
G03X611999Y253500I7587J7587D01*
G01X601011Y261600D02*
X605191Y257421D01*
G01D02*
G03X612000Y254600I6810J6809D01*
G01X593065Y284182D02*
Y283227D01*
G01D02*
G03X593405Y282406I1161J0D01*
G01D02*
X599810Y276001D01*
G01D02*
Y276000D01*
G01X598710Y275545D02*
Y275544D01*
G01X595955Y290900D02*
G03X598045Y285854I7136J0D01*
G01D02*
X609914Y273985D01*
G01X598823Y286632D02*
X610692Y274763D01*
G01X605500Y287500D02*
X606750Y286250D01*
G01D02*
G03X621597Y280100I14847J14847D01*
G01X604722Y286722D02*
X605972Y285472D01*
G01D02*
G03X621596Y279000I15625J15625D01*
G01X592832Y290863D02*
G03Y293168I-1152J1153D01*
G01X596259Y298230D02*
X594403Y296374D01*
G01D02*
G02X593500Y296000I-903J903D01*
G01X600055Y310194D02*
Y297762D01*
G01D02*
X600054Y297763D01*
G01D02*
G02X598777Y294678I-4363J-1D01*
G01D02*
X597703Y293605D01*
G01D02*
X596630Y292532D01*
G01D02*
G03X595955Y290900I1632J-1631D01*
G01X601155Y310195D02*
Y297763D01*
G01D02*
G02X599555Y293900I-5463J0D01*
G01D02*
X597408Y291754D01*
G01D02*
G03X597055Y290900I854J-853D01*
G01D02*
G03X598823Y286632I6036J0D01*
G01X608069Y290355D02*
X610001Y292287D01*
G01X609647Y293854D02*
G03X608086Y294500I-1560J-1561D01*
G01D02*
X608000D01*
G01D02*
G03X606293Y293793I0J-2414D01*
G01D02*
X605000Y292500D01*
G01D02*
G03X604500Y291293I1207J-1207D01*
G01D02*
Y289000D01*
G01D02*
G03X604854Y288147I1207J1D01*
G01D02*
X605500Y287500D01*
G01X610354Y296574D02*
G02X608001Y295600I-2352J2353D01*
G01D02*
G03X605515Y294571I-1J-3514D01*
G01D02*
X604222Y293278D01*
G01D02*
G03X603400Y291294I1985J-1985D01*
G01D02*
Y288999D01*
G01D02*
G03X604076Y287369I2307J1D01*
G01D02*
X604722Y286722D01*
G01X600199Y315945D02*
X601697Y312947D01*
G01D02*
G02X601473Y312276I-448J-223D01*
G01D02*
X601472D01*
G01D02*
X601244Y312163D01*
G01D02*
X600892Y311987D01*
G01D02*
G03X600055Y310194I1499J-1792D01*
G01X604134Y308070D02*
X602637Y311068D01*
G01D02*
G03X601966Y311292I-447J-223D01*
G01D02*
X601965D01*
G01D02*
X601962Y311291D01*
G01D02*
X601517Y311069D01*
G01D02*
G03X601155Y310195I874J-874D01*
G01X598197Y320500D02*
G03X599472Y321028I0J1803D01*
G01D02*
X600222Y321778D01*
G01D02*
G02X602930Y322900I2709J-2709D01*
G01D02*
X868369D01*
G01X598197Y319400D02*
G03X600250Y320250I0J2903D01*
G01D02*
X601000Y321000D01*
G01D02*
G02X602931Y321800I1931J-1931D01*
G01D02*
X868369D01*
G01X592779Y335221D02*
X593160Y335604D01*
G01D02*
G02X597500Y337401I4339J-4341D01*
G01X593627Y328228D02*
G02X596699Y329500I3071J-3072D01*
G01D02*
X1168138D01*
G01X594405Y327450D02*
G02X596699Y328400I2294J-2294D01*
G01D02*
X1168137D01*
G01X597500Y338501D02*
X597501Y338500D01*
G01D02*
X700257D01*
G01X597500Y337401D02*
G02X597609Y337400I-2J-6138D01*
G01D02*
X700257D01*
G01X595325Y347268D02*
G02X597093Y348000I1768J-1768D01*
G01D02*
X627676D01*
G01X594547Y348046D02*
G02X597094Y349100I2545J-2546D01*
G01D02*
X722106D01*
G01X611999Y253500D02*
X698135D01*
G01X615712Y265550D02*
X709595D01*
G01X615712Y264450D02*
X709595D01*
G01X612000Y254600D02*
X615316D01*
G01D02*
G03X615906Y254895I-26J790D01*
G01D02*
G02X616496Y255190I616J-495D01*
G01D02*
X617996D01*
G01D02*
G02X618586Y254895I-26J-790D01*
G01D02*
G03X619176Y254600I616J495D01*
G01D02*
X620676D01*
G01D02*
G03X621266Y254895I-26J790D01*
G01D02*
G02X621856Y255190I616J-495D01*
G01D02*
X623356D01*
G01D02*
G02X623946Y254895I-26J-790D01*
G01D02*
G03X624536Y254600I616J495D01*
G01D02*
X626036D01*
G01X609914Y273985D02*
G03X617000Y271050I7086J7086D01*
G01D02*
X713700D01*
G01X610692Y274763D02*
G03X617000Y272150I6308J6308D01*
G01D02*
X713700D01*
G01X621597Y280100D02*
X624753D01*
G01D02*
G03X625343Y280395I-26J790D01*
G01D02*
G02X625933Y280690I616J-494D01*
G01X621596Y279000D02*
X716778D01*
G01X610001Y292287D02*
G03Y293499I-606J606D01*
G01D02*
X609647Y293854D01*
G01X612009Y298230D02*
X610354Y296574D01*
G01X626036Y254600D02*
G03X626626Y254895I-26J790D01*
G01D02*
G02X627216Y255190I616J-495D01*
G01D02*
X628716D01*
G01D02*
G02X629306Y254895I-26J-790D01*
G01D02*
G03X629896Y254600I616J495D01*
G01D02*
X638335D01*
G01D02*
G03X638925Y254895I-26J789D01*
G01D02*
G02X639515Y255190I616J-495D01*
G01D02*
X641015D01*
G01D02*
G02X641605Y254895I-26J-789D01*
G01D02*
G03X642195Y254600I616J495D01*
G01X625933Y280690D02*
X627433D01*
G01D02*
G02X628023Y280395I-26J-790D01*
G01D02*
G03X628613Y280100I616J494D01*
G01D02*
X630113D01*
G01D02*
G03X630703Y280395I-26J790D01*
G01D02*
G02X631293Y280690I616J-494D01*
G01D02*
X632793D01*
G01D02*
G02X633383Y280395I-26J-790D01*
G01D02*
G03X633973Y280100I616J494D01*
G01D02*
X635473D01*
G01D02*
G03X636063Y280395I-26J790D01*
G01D02*
G02X636653Y280690I616J-494D01*
G01D02*
X638153D01*
G01D02*
G02X638743Y280395I-26J-790D01*
G01D02*
G03X639333Y280100I616J494D01*
G01D02*
X645883D01*
G01X627676Y348000D02*
G02X628266Y347705I-26J-790D01*
G01D02*
G03X628856Y347410I616J494D01*
G01D02*
X630356D01*
G01D02*
G03X630946Y347705I-26J790D01*
G01D02*
G02X631536Y348000I616J-494D01*
G01D02*
X633036D01*
G01D02*
G02X633626Y347705I-26J-790D01*
G01D02*
G03X634216Y347410I616J494D01*
G01D02*
X635716D01*
G01D02*
G03X636306Y347705I-26J790D01*
G01D02*
G02X636896Y348000I616J-494D01*
G01D02*
X638396D01*
G01D02*
G02X638986Y347705I-26J-790D01*
G01D02*
G03X639576Y347410I616J494D01*
G01D02*
X641076D01*
G01D02*
G03X641666Y347705I-26J790D01*
G01D02*
G02X642256Y348000I616J-494D01*
G01X642195Y254600D02*
X643695D01*
G01D02*
G03X644285Y254895I-26J789D01*
G01D02*
G02X644875Y255190I616J-495D01*
G01D02*
X646375D01*
G01D02*
G02X646965Y254895I-26J-789D01*
G01D02*
G03X647555Y254600I616J495D01*
G01D02*
X649055D01*
G01D02*
G03X649645Y254895I-26J789D01*
G01D02*
G02X650235Y255190I616J-495D01*
G01D02*
X651735D01*
G01D02*
G02X652325Y254895I-26J-789D01*
G01D02*
G03X652915Y254600I616J495D01*
G01D02*
X662095D01*
G01X645883Y280100D02*
G03X646473Y280395I-26J790D01*
G01D02*
G02X647063Y280690I616J-495D01*
G01D02*
X648563D01*
G01D02*
G02X649153Y280395I-26J-790D01*
G01D02*
G03X649743Y280100I616J495D01*
G01D02*
X651243D01*
G01D02*
G03X651833Y280395I-26J790D01*
G01D02*
G02X652423Y280690I616J-495D01*
G01D02*
X653923D01*
G01D02*
G02X654513Y280395I-26J-790D01*
G01D02*
G03X655103Y280100I616J495D01*
G01D02*
X656603D01*
G01D02*
G03X657193Y280395I-26J790D01*
G01D02*
G02X657783Y280690I616J-495D01*
G01D02*
X659283D01*
G01X642256Y348000D02*
X646495D01*
G01D02*
G02X647085Y347705I-26J-790D01*
G01D02*
G03X647675Y347410I616J495D01*
G01D02*
X649175D01*
G01D02*
G03X649765Y347705I-26J790D01*
G01D02*
G02X650355Y348000I616J-495D01*
G01D02*
X651855D01*
G01D02*
G02X652445Y347705I-26J-790D01*
G01D02*
G03X653035Y347410I616J495D01*
G01D02*
X654535D01*
G01D02*
G03X655125Y347705I-26J790D01*
G01D02*
G02X655715Y348000I616J-495D01*
G01D02*
X657215D01*
G01D02*
G02X657805Y347705I-26J-790D01*
G01D02*
G03X658395Y347410I616J495D01*
G01X662095Y254600D02*
G03X662685Y254895I-26J790D01*
G01D02*
G02X663275Y255190I616J-495D01*
G01D02*
X664775D01*
G01D02*
G02X665365Y254895I-26J-790D01*
G01D02*
G03X665955Y254600I616J495D01*
G01D02*
X698136D01*
G01X659283Y280690D02*
G02X659873Y280395I-26J-790D01*
G01D02*
G03X660463Y280100I616J495D01*
G01D02*
X716778D01*
G01X658395Y347410D02*
X659895D01*
G01D02*
G03X660485Y347705I-26J790D01*
G01D02*
G02X661075Y348000I616J-495D01*
G01D02*
X680161D01*
G01D02*
G02X680751Y347705I-26J-789D01*
G01D02*
G03X681341Y347410I616J495D01*
G01D02*
X682841D01*
G01D02*
G03X683431Y347705I-26J789D01*
G01D02*
G02X684021Y348000I616J-495D01*
G01D02*
X685521D01*
G01D02*
G02X686111Y347705I-26J-789D01*
G01D02*
G03X686701Y347410I616J495D01*
G01D02*
X688201D01*
G01D02*
G03X688791Y347705I-26J789D01*
G01D02*
G02X689381Y348000I616J-495D01*
G01D02*
X690881D01*
G01D02*
G02X691471Y347705I-26J-789D01*
G01X698135Y253500D02*
G02X699685Y252858I0J-2191D01*
G01D02*
G03X702000Y251899I2315J2315D01*
G01D02*
Y251900D01*
G01D02*
X904617D01*
G01X698136Y254600D02*
G02X700463Y253636I0J-3291D01*
G01D02*
G03X702000Y253000I1536J1537D01*
G01D02*
X904616D01*
G01X702126Y336626D02*
X703196Y335556D01*
G01D02*
G03X704539Y335000I1343J1344D01*
G01D02*
X1180992D01*
G01X700257Y338500D02*
G02X702904Y337404I1J-3743D01*
G01D02*
X703974Y336334D01*
G01D02*
G03X704539Y336100I565J565D01*
G01D02*
X1180992D01*
G01X700257Y337400D02*
G02X702126Y336626I0J-2643D01*
G01X691471Y347705D02*
G03X692061Y347410I616J495D01*
G01D02*
X693561D01*
G01D02*
G03X694151Y347705I-26J789D01*
G01D02*
G02X694741Y348000I616J-495D01*
G01D02*
X722106D01*
G01X709595Y265550D02*
G02X715322Y263178I0J-8100D01*
G01D02*
X717100Y261400D01*
G01D02*
G03X720721Y259900I3621J3621D01*
G01D02*
X901440D01*
G01X709595Y264450D02*
G02X714544Y262400I0J-7000D01*
G01D02*
X716322Y260622D01*
G01D02*
G03X720720Y258800I4399J4399D01*
G01D02*
X901440D01*
G01X713700Y271050D02*
G02X717446Y269499I1J-5297D01*
G01D02*
X717472Y269472D01*
G01D02*
X719172Y267772D01*
G01D02*
G03X724899Y265400I5727J5728D01*
G01X718264Y270236D02*
X719950Y268550D01*
G01D02*
G03X724899Y266500I4949J4950D01*
G01X713700Y272150D02*
Y272151D01*
G01D02*
G02X718232Y270270I1J-6398D01*
G01D02*
X718264Y270236D01*
G01X716778Y280100D02*
G02X720400Y278600I0J-5122D01*
G01D02*
X722650Y276350D01*
G01D02*
G03X729531Y273500I6881J6881D01*
G01X716778Y279000D02*
G02X719622Y277822I0J-4022D01*
G01D02*
X721872Y275572D01*
G01D02*
G03X729531Y272400I7658J7659D01*
G01X721600Y288405D02*
G03X722890Y285290I4405J0D01*
G01D02*
X727257Y280923D01*
G01X722700Y288405D02*
G03X723668Y286068I3305J0D01*
G01D02*
X728035Y281701D01*
G01X718309Y290355D02*
X718308Y291868D01*
G01D02*
G02X720408Y293110I1418J-1D01*
G01D02*
G02X720611Y292975I-681J-1243D01*
G01D02*
G02X720729Y292871I-877J-1114D01*
G01D02*
X721176Y292425D01*
G01D02*
G02X721600Y291400I-1025J-1024D01*
G01D02*
Y288405D01*
G01X722244Y298230D02*
G03X721557Y296571I1659J-1659D01*
G01D02*
Y294754D01*
G01D02*
G03X722060Y293540I1717J0D01*
G01D02*
G02X722700Y291400I-3261J-2141D01*
G01D02*
Y288405D01*
G01X722106Y348000D02*
G02X726273Y346274I0J-5893D01*
G01X722106Y349100D02*
G02X727051Y347052I0J-6993D01*
G01X724899Y265400D02*
X897500D01*
G01X724899Y266500D02*
X897500D01*
G01X729531Y273500D02*
X894257D01*
G01X729531Y272400D02*
X894257D01*
G01X727257Y280923D02*
G03X731900Y279000I4643J4644D01*
G01D02*
X889928D01*
G01X728035Y281701D02*
G03X731900Y280100I3865J3865D01*
G01D02*
X889928D01*
G01X739155Y286755D02*
G03X741943Y285600I2789J2789D01*
G01X733580Y308531D02*
Y297435D01*
G01D02*
G03X734475Y295275I3056J1D01*
G01D02*
X736725Y293025D01*
G01D02*
G02X737200Y291878I-1146J-1146D01*
G01D02*
Y289900D01*
G01D02*
G03X738041Y287869I2873J0D01*
G01D02*
X739155Y286755D01*
G01X734680Y308531D02*
Y297436D01*
G01D02*
G03X735253Y296053I1956J0D01*
G01D02*
X737503Y293803D01*
G01D02*
G02X738300Y291879I-1924J-1924D01*
G01D02*
Y289900D01*
G01D02*
G03X738819Y288647I1772J0D01*
G01D02*
X739933Y287533D01*
G01D02*
G03X741944Y286700I2011J2011D01*
G01X730119Y308070D02*
X729000Y309189D01*
G01D02*
G02Y311500I1156J1156D01*
G01D02*
G02X729966Y311900I966J-966D01*
G01D02*
X730742D01*
G01D02*
G02X731285Y311675I0J-768D01*
G01D02*
X732980Y309980D01*
G01D02*
G02X733580Y308531I-1449J-1449D01*
G01X726179Y315945D02*
X728254Y313870D01*
G01D02*
X728700Y313425D01*
G01D02*
G03X729570Y313064I871J870D01*
G01D02*
X730700D01*
G01D02*
G02X731983Y312532I-1J-1815D01*
G01D02*
X732058Y312458D01*
G01D02*
X733758Y310758D01*
G01D02*
G02X734680Y308531I-2227J-2226D01*
G01X726273Y346274D02*
X728813Y343734D01*
G01D02*
G03X733000Y342000I4187J4188D01*
G01D02*
X1187019D01*
G01X727051Y347052D02*
X729591Y344512D01*
G01D02*
G03X733000Y343100I3409J3409D01*
G01D02*
X1187019D01*
G01X741943Y285600D02*
X886610D01*
G01X741944Y286700D02*
X886610D01*
G01X868369Y322900D02*
G02X869712Y322344I0J-1900D01*
G01D02*
X870718Y321338D01*
G01D02*
G03X872500Y320600I1782J1782D01*
G01X868369Y321800D02*
G02X868934Y321566I0J-799D01*
G01D02*
X869940Y320560D01*
G01D02*
G03X872500Y319500I2560J2561D01*
G01X886610Y285600D02*
G03X890563Y287237I1J5590D01*
G01X886610Y286700D02*
G03X889785Y288015I0J4490D01*
G01X872500Y320600D02*
X909769D01*
G01X872500Y319500D02*
X909769D01*
G01X901440Y259900D02*
G03X908200Y262700I0J9560D01*
G01X901440Y258800D02*
G03X908978Y261922I0J10660D01*
G01X897500Y265400D02*
G03X905960Y268904I0J11965D01*
G01X897500Y266500D02*
G03X905182Y269682I0J10864D01*
G01X894257Y273500D02*
G03X901500Y276500I0J10243D01*
G01D02*
X920900Y295900D01*
G01X894257Y272400D02*
G03X902278Y275722I1J11343D01*
G01D02*
X921678Y295122D01*
G01X889928Y279000D02*
G03X897828Y282272I0J11172D01*
G01D02*
X919262Y303706D01*
G01X889928Y280100D02*
G03X897050Y283050I0J10072D01*
G01D02*
X918484Y304484D01*
G01X890563Y287237D02*
X914813Y311487D01*
G01X889785Y288015D02*
X914035Y312265D01*
G01X904617Y251900D02*
G03X912878Y255322I-1J11684D01*
G01X904616Y253000D02*
G03X912100Y256100I0J10584D01*
G01X908200Y262700D02*
X921182Y275682D01*
G01X908978Y261922D02*
X921960Y274904D01*
G01X905960Y268904D02*
X919028Y281972D01*
G01X905182Y269682D02*
X918250Y282750D01*
G01X912878Y255322D02*
X926528Y268972D01*
G01X912100Y256100D02*
X925750Y269750D01*
G01X919028Y281972D02*
G02X928511Y285900I9483J-9483D01*
G01X918250Y282750D02*
G02X928510Y287000I10261J-10261D01*
G01X920900Y295900D02*
G02X929592Y299500I8692J-8692D01*
G01X919262Y303706D02*
G02X924800Y306000I5538J-5538D01*
G01X918484Y304484D02*
G02X924800Y307100I6316J-6317D01*
G01X914813Y311487D02*
G02X920638Y313900I5825J-5825D01*
G01D02*
X1154000D01*
G01X914035Y312265D02*
G02X920637Y315000I6603J-6603D01*
G01D02*
X1154000D01*
G01X909769Y320600D02*
G03X910334Y320834I0J799D01*
G01D02*
X911250Y321750D01*
G01D02*
G02X913666Y322750I2415J-2415D01*
G01D02*
X1160501D01*
G01X909769Y319500D02*
G03X911112Y320056I0J1900D01*
G01D02*
X912028Y320972D01*
G01D02*
G02X913665Y321650I1637J-1637D01*
G01D02*
X1160500D01*
G01X926528Y268972D02*
G02X932631Y271500I6103J-6103D01*
G01X925750Y269750D02*
G02X932630Y272600I6881J-6881D01*
G01X921182Y275682D02*
G02X930400Y279500I9218J-9219D01*
G01D02*
X1172098D01*
G01X921960Y274904D02*
G02X930400Y278400I8440J-8440D01*
G01D02*
X1172099D01*
G01X928511Y285900D02*
X1086934D01*
G01X932631Y271500D02*
X1172500D01*
G01X932630Y272600D02*
X1172500D01*
G01X928510Y287000D02*
X938504D01*
G01X929592Y299500D02*
X1171403D01*
G01X921678Y295122D02*
G02X929592Y298400I7914J-7914D01*
G01D02*
X1171404D01*
G01X924800Y306000D02*
X1163100D01*
G01X924800Y307100D02*
X1162500D01*
G01X938504Y287000D02*
G03X939094Y287295I-26J790D01*
G01D02*
G02X939684Y287590I616J-495D01*
G01D02*
X941184D01*
G01D02*
G02X941774Y287295I-26J-790D01*
G01D02*
G03X942364Y287000I616J495D01*
G01D02*
X943864D01*
G01D02*
G03X944454Y287295I-26J790D01*
G01D02*
G02X945044Y287590I616J-495D01*
G01D02*
X946544D01*
G01D02*
G02X947134Y287295I-26J-790D01*
G01D02*
G03X947724Y287000I616J495D01*
G01D02*
X949224D01*
G01D02*
G03X949814Y287295I-26J790D01*
G01D02*
G02X950404Y287590I616J-495D01*
G01D02*
X951904D01*
G01D02*
G02X952494Y287295I-26J-790D01*
G01D02*
G03X953084Y287000I616J495D01*
G01D02*
X973234D01*
G01D02*
G03X973824Y287295I-26J790D01*
G01D02*
G02X974414Y287590I616J-494D01*
G01D02*
X975914D01*
G01D02*
G02X976504Y287295I-26J-790D01*
G01D02*
G03X977094Y287000I616J494D01*
G01D02*
X978594D01*
G01D02*
G03X979184Y287295I-26J790D01*
G01D02*
G02X979774Y287590I616J-494D01*
G01D02*
X981274D01*
G01D02*
G02X981864Y287295I-26J-790D01*
G01D02*
G03X982454Y287000I616J494D01*
G01D02*
X983954D01*
G01D02*
G03X984544Y287295I-26J790D01*
G01D02*
G02X985134Y287590I616J-494D01*
G01D02*
X986634D01*
G01D02*
G02X987224Y287295I-26J-790D01*
G01D02*
G03X987814Y287000I616J494D01*
G01D02*
X1005787D01*
G01D02*
G03X1006377Y287295I-26J790D01*
G01D02*
G02X1006967Y287590I616J-494D01*
G01D02*
X1008467D01*
G01D02*
G02X1009057Y287295I-26J-790D01*
G01D02*
G03X1009647Y287000I616J494D01*
G01D02*
X1011147D01*
G01D02*
G03X1011737Y287295I-26J790D01*
G01D02*
G02X1012327Y287590I616J-494D01*
G01D02*
X1013827D01*
G01D02*
G02X1014417Y287295I-26J-790D01*
G01D02*
G03X1015007Y287000I616J494D01*
G01D02*
X1016507D01*
G01D02*
G03X1017097Y287295I-26J790D01*
G01D02*
G02X1017687Y287590I616J-494D01*
G01D02*
X1019187D01*
G01D02*
G02X1019777Y287295I-26J-790D01*
G01D02*
G03X1020367Y287000I616J494D01*
G01D02*
X1086933D01*
G01X1086934Y285900D02*
G02X1087900Y285500I0J-1366D01*
G01D02*
G03X1089107Y285000I1207J1207D01*
G01D02*
X1169367D01*
G01X1086933Y287000D02*
G02X1088678Y286278I2J-2466D01*
G01D02*
G03X1089108Y286100I429J429D01*
G01D02*
X1169368D01*
G01X1119250Y766750D02*
X1116080Y769920D01*
G01D02*
G02X1114100Y774700I4780J4780D01*
G01D02*
Y803544D01*
G01X1113000D02*
Y774700D01*
G01D02*
G03X1115302Y769142I7861J0D01*
G01D02*
X1118472Y765972D01*
G01X1114100Y803544D02*
G02X1115200Y806200I3756J0D01*
G01D02*
X1121150Y812150D01*
G01X1120372Y812928D02*
X1114422Y806978D01*
G01D02*
G03X1113000Y803544I3434J-3433D01*
G01X1124000Y729000D02*
G02X1122900Y731656I2656J2656D01*
G01X1121022Y730022D02*
X1120500Y729500D01*
G01X1122900Y731656D02*
Y731900D01*
G01D02*
G03X1122052Y733948I-2897J0D01*
G01D02*
X1121550Y734450D01*
G01D02*
G02X1121000Y735778I1328J1328D01*
G01D02*
Y762526D01*
G01X1119900Y762525D02*
Y735778D01*
G01D02*
G03X1120772Y733672I2978J0D01*
G01D02*
X1121274Y733170D01*
G01D02*
G02X1121800Y731900I-1270J-1270D01*
G01D02*
G02X1121022Y730022I-2656J0D01*
G01X1121000Y762526D02*
G03X1119250Y766750I-5975J-1D01*
G01X1118472Y765972D02*
G02X1119900Y762525I-3447J-3447D01*
G01X1121150Y812150D02*
G02X1125616Y814000I4466J-4466D01*
G01D02*
X1170894D01*
G01X1170895Y815100D02*
X1125615D01*
G01D02*
G03X1120372Y812928I1J-7416D01*
G01X1163418Y321542D02*
X1166176Y318784D01*
G01D02*
G03X1170000Y317200I3824J3824D01*
G01X1162952Y320452D02*
X1165398Y318006D01*
G01D02*
G03X1170000Y316100I4602J4603D01*
G01X1163100Y306000D02*
G02X1163894Y305671I0J-1123D01*
G01D02*
X1165000Y304565D01*
G01X1162500Y307100D02*
G03X1164932Y308108I-1J3440D01*
G01D02*
X1165000Y308175D01*
G01X1154000Y313900D02*
G02X1155698Y313196I-1J-2402D01*
G01D02*
X1156100Y312795D01*
G01X1154000Y315000D02*
G03X1155187Y315491I1J1678D01*
G01D02*
X1156100Y316405D01*
G01X1160501Y322750D02*
G02X1163418Y321542I0J-4127D01*
G01X1160500Y321650D02*
G02X1162640Y320763I-1J-3027D01*
G01D02*
X1162952Y320452D01*
G01X1172098Y279500D02*
G03X1173638Y280138I0J2178D01*
G01D02*
X1180000Y286500D01*
G01D02*
X1180439Y286940D01*
G01X1172099Y278400D02*
G03X1174416Y279360I-1J3278D01*
G01D02*
X1181218Y286162D01*
G01D02*
G03X1182600Y289499I-3339J3338D01*
G01X1169367Y285000D02*
G03X1171285Y285785I1J2732D01*
G01D02*
X1171314Y285812D01*
G01D02*
G03X1172101Y287700I-1869J1887D01*
G01X1169368Y286100D02*
G03X1170522Y286578I0J1632D01*
G01D02*
X1170545Y286600D01*
G01X1172500Y271500D02*
G03X1179328Y274328I0J9657D01*
G01D02*
X1190584Y285584D01*
G01X1172500Y272600D02*
G03X1178550Y275106I0J8556D01*
G01D02*
X1189472Y286028D01*
G01X1180439Y286940D02*
G03X1181500Y289500I-2560J2561D01*
G01D02*
Y291326D01*
G01D02*
G02X1182722Y294278I4173J1D01*
G01D02*
X1183697Y295254D01*
G01X1182600Y289499D02*
Y291327D01*
G01D02*
G02X1183500Y293500I3073J0D01*
G01D02*
X1184475Y294476D01*
G01X1172101Y287700D02*
X1172100D01*
G01D02*
Y288448D01*
G01D02*
G02X1173777Y290125I1677J0D01*
G01X1170545Y286600D02*
G03X1171000Y287700I-1100J1099D01*
G01D02*
Y288400D01*
G01D02*
G03X1170645Y289257I-1212J0D01*
G01D02*
X1169777Y290125D01*
G01X1171403Y299500D02*
G03X1174300Y300700I0J4097D01*
G01D02*
X1174794Y301194D01*
G01D02*
G02X1183500Y304800I8706J-8706D01*
G01X1171404Y298400D02*
G03X1175078Y299922I-1J5197D01*
G01D02*
X1175572Y300416D01*
G01D02*
G02X1183499Y303700I7928J-7928D01*
G01X1170000Y317200D02*
X1222710D01*
G01X1170000Y316100D02*
X1176067D01*
G01D02*
G02X1176657Y315805I-26J-790D01*
G01D02*
G03X1177247Y315510I616J495D01*
G01D02*
X1178747D01*
G01D02*
G03X1179337Y315805I-26J790D01*
G01D02*
G02X1179927Y316100I616J-495D01*
G01D02*
X1181427D01*
G01D02*
G02X1182017Y315805I-26J-789D01*
G01D02*
G03X1182607Y315510I616J495D01*
G01D02*
X1184107D01*
G01X1183500Y304800D02*
X1215569D01*
G01X1183499Y303700D02*
X1215568D01*
G01X1180992Y336100D02*
G02X1183190Y335190I1J-3108D01*
G01D02*
X1183327Y335053D01*
G01D02*
G03X1185000Y334360I1673J1673D01*
G01X1180992Y335000D02*
G02X1182412Y334412I0J-2008D01*
G01D02*
X1182549Y334275D01*
G01D02*
G03X1185000Y333260I2451J2452D01*
G01X1168138Y329500D02*
G02X1170559Y328497I-1J-3425D01*
G01D02*
X1171278Y327778D01*
G01D02*
G02X1171870Y326348I-1430J-1430D01*
G01D02*
Y325500D01*
G01D02*
G03X1172244Y324597I1277J0D01*
G01D02*
X1173125Y323716D01*
G01X1168137Y328400D02*
G02X1169781Y327719I0J-2325D01*
G01D02*
X1170500Y327000D01*
G01D02*
G02X1170770Y326348I-652J-652D01*
G01D02*
Y325500D01*
G01D02*
G02X1170396Y324597I-1277J0D01*
G01D02*
X1169515Y323716D01*
G01X1183623Y690811D02*
X1182817Y690005D01*
G01D02*
Y689155D01*
G01X1186091Y691911D02*
X1182478D01*
G01D02*
X1179678Y689111D01*
G01X1170894Y814000D02*
G02X1177050Y811450I0J-8706D01*
G01D02*
X1189850Y798650D01*
G01X1190628Y799428D02*
X1177828Y812228D01*
G01D02*
G03X1170895Y815100I-6934J-6934D01*
G01X1190584Y285584D02*
G03X1191377Y287499I-1917J1916D01*
G01X1189472Y286028D02*
X1189805Y286362D01*
G01D02*
G03X1190277Y287500I-1138J1139D01*
G01X1183697Y295254D02*
G02X1185500Y296001I1803J-1803D01*
G01D02*
Y296000D01*
G01D02*
X1188798D01*
G01D02*
G03X1189388Y296295I-26J790D01*
G01D02*
G02X1189978Y296590I616J-495D01*
G01D02*
X1191478D01*
G01D02*
G02X1192068Y296295I-26J-790D01*
G01D02*
G03X1192658Y296000I616J495D01*
G01D02*
X1194158D01*
G01D02*
G03X1194748Y296295I-26J790D01*
G01D02*
G02X1195338Y296590I616J-495D01*
G01D02*
X1196838D01*
G01D02*
G02X1197428Y296295I-26J-790D01*
G01D02*
G03X1198018Y296000I616J495D01*
G01D02*
X1199518D01*
G01D02*
G03X1200108Y296295I-26J790D01*
G01X1184475Y294476D02*
G02X1185500Y294900I1024J-1025D01*
G01D02*
X1204878D01*
G01X1191377Y287499D02*
Y288000D01*
G01D02*
G02X1191684Y288741I1048J0D01*
G01D02*
X1192743Y289800D01*
G01X1190277Y287500D02*
Y288000D01*
G01D02*
G03X1189994Y288683I-966J0D01*
G01D02*
X1188877Y289800D01*
G01X1184107Y315510D02*
G03X1184697Y315805I-26J789D01*
G01D02*
G02X1185287Y316100I616J-495D01*
G01D02*
X1186787D01*
G01D02*
G02X1187377Y315805I-26J-789D01*
G01D02*
G03X1187967Y315510I616J495D01*
G01D02*
X1189467D01*
G01D02*
G03X1190057Y315805I-26J789D01*
G01D02*
G02X1190647Y316100I616J-495D01*
G01D02*
X1192147D01*
G01D02*
G02X1192737Y315805I-26J-789D01*
G01D02*
G03X1193327Y315510I616J495D01*
G01D02*
X1194827D01*
G01D02*
G03X1195417Y315805I-26J789D01*
G01D02*
G02X1196007Y316100I616J-495D01*
G01D02*
X1204474D01*
G01X1185000Y334360D02*
X1232200D01*
G01X1185000Y333260D02*
X1232200D01*
G01X1187019Y342000D02*
G02X1189127Y341127I0J-2981D01*
G01D02*
G03X1191366Y340200I2238J2239D01*
G01D02*
X1196365D01*
G01D02*
G03X1197494Y340668I-1J1598D01*
G01D02*
X1197913Y341087D01*
G01D02*
G03X1198430Y342335I-1248J1248D01*
G01D02*
Y343000D01*
G01D02*
G02X1198665Y343569I804J1D01*
G01D02*
X1199685Y344588D01*
G01X1187019Y343100D02*
G02X1189905Y341905I1J-4081D01*
G01D02*
G03X1191366Y341300I1461J1461D01*
G01D02*
X1196364D01*
G01D02*
G03X1196716Y341446I0J498D01*
G01D02*
X1197135Y341865D01*
G01D02*
G03X1197330Y342336I-470J470D01*
G01D02*
Y343000D01*
G01D02*
G03X1197095Y343569I-804J1D01*
G01D02*
X1196075Y344588D01*
G01X1215966Y694900D02*
X1190636D01*
G01D02*
X1186547Y690811D01*
G01D02*
X1183623D01*
G01X1215510Y696000D02*
X1190180D01*
G01D02*
X1186091Y691911D01*
G01X1216944Y690300D02*
X1194300D01*
G01D02*
X1193011Y689011D01*
G01D02*
Y685486D01*
G01D02*
X1192937Y683911D01*
G01X1217850Y691400D02*
X1193844D01*
G01D02*
X1191911Y689467D01*
G01D02*
Y687056D01*
G01D02*
X1189938Y685083D01*
G01D02*
X1189890Y684053D01*
G01X1193486Y783513D02*
X1224900Y752099D01*
G01X1226000Y752555D02*
X1194586Y783969D01*
G01X1189850Y798650D02*
G02X1191900Y793701I-4949J-4949D01*
G01D02*
Y787998D01*
G01D02*
X1193486Y783770D01*
G01D02*
Y783513D01*
G01X1194586Y783969D02*
Y783970D01*
G01D02*
X1193000Y788200D01*
G01D02*
Y793702D01*
G01D02*
G03X1190628Y799428I-8099J-1D01*
G01X1209827Y292850D02*
X1222838Y279839D01*
G01X1200108Y296295D02*
G02X1200698Y296590I616J-495D01*
G01D02*
X1202198D01*
G01D02*
G02X1202788Y296295I-26J-790D01*
G01D02*
G03X1203378Y296000I616J495D01*
G01D02*
X1204878D01*
G01D02*
G02X1210605Y293628I0J-8099D01*
G01D02*
X1211666Y292567D01*
G01D02*
G03X1212291Y292359I539J577D01*
G01D02*
G02X1212917Y292150I86J-785D01*
G01D02*
X1213978Y291089D01*
G01D02*
G02X1214186Y290464I-577J-539D01*
G01D02*
G03X1214395Y289838I786J-86D01*
G01D02*
X1215456Y288777D01*
G01D02*
G03X1216082Y288569I539J577D01*
G01D02*
G02X1216707Y288360I85J-785D01*
G01X1204878Y294900D02*
G02X1209827Y292850I0J-6999D01*
G01X1204474Y316100D02*
G02X1205064Y315805I-26J-790D01*
G01D02*
G03X1205654Y315510I616J495D01*
G01D02*
X1207154D01*
G01D02*
G03X1207744Y315805I-26J790D01*
G01D02*
G02X1208334Y316100I616J-495D01*
G01D02*
X1209834D01*
G01D02*
G02X1210424Y315805I-26J-790D01*
G01D02*
G03X1211014Y315510I616J495D01*
G01D02*
X1212514D01*
G01D02*
G03X1213104Y315805I-26J790D01*
G01D02*
G02X1213694Y316100I616J-495D01*
G01D02*
X1222710D01*
G01X1215569Y304800D02*
G02X1217500Y304000I0J-2731D01*
G01X1215568Y303700D02*
G02X1216722Y303222I0J-1631D01*
G01X1222966Y701900D02*
X1215966Y694900D01*
G01X1222510Y703000D02*
X1215510Y696000D01*
G01X1217977Y286674D02*
G03X1218185Y286048I785J-87D01*
G01D02*
X1219246Y284987D01*
G01D02*
G03X1219872Y284779I539J577D01*
G01D02*
G02X1220497Y284570I85J-786D01*
G01D02*
X1221558Y283509D01*
G01D02*
G02X1221767Y282884I-576J-540D01*
G01D02*
G03X1221975Y282258I785J-87D01*
G01D02*
X1223616Y280617D01*
G01D02*
X1224155Y280079D01*
G01D02*
G03X1227000Y278900I2845J2843D01*
G01D02*
X1228499D01*
G01D02*
G03X1229089Y279195I-26J790D01*
G01D02*
G02X1229679Y279490I616J-495D01*
G01D02*
X1231179D01*
G01D02*
G02X1231769Y279195I-26J-790D01*
G01D02*
G03X1232359Y278900I616J495D01*
G01D02*
X1233859D01*
G01X1222838Y279839D02*
X1223377Y279301D01*
G01D02*
G03X1227000Y277800I3623J3622D01*
G01D02*
X1252204D01*
G01X1216707Y288360D02*
X1217768Y287299D01*
G01D02*
G02X1217977Y286674I-576J-540D01*
G01X1217500Y304000D02*
X1232750Y288750D01*
G01D02*
G03X1238665Y286300I5915J5915D01*
G01X1216722Y303222D02*
X1231972Y287972D01*
G01D02*
G03X1238665Y285200I6693J6693D01*
G01X1222710Y317200D02*
G02X1225178Y316178I0J-3490D01*
G01D02*
X1225678Y315678D01*
G01D02*
G03X1229403Y314135I3725J3725D01*
G01D02*
X1233846D01*
G01X1222710Y316100D02*
G02X1224400Y315400I0J-2390D01*
G01D02*
X1224900Y314900D01*
G01D02*
G03X1229402Y313035I4503J4503D01*
G01D02*
X1233845D01*
G01X1232200Y334360D02*
G02X1237616Y332117I0J-7659D01*
G01X1232200Y333260D02*
G02X1236838Y331339I0J-6559D01*
G01X1250549Y695451D02*
X1223457D01*
G01D02*
X1218306Y690300D01*
G01D02*
X1217397D01*
G01D02*
X1217396Y690299D01*
G01D02*
X1216945D01*
G01D02*
X1216944Y690300D01*
G01X1234871Y696551D02*
X1231697D01*
G01D02*
X1231107Y697141D01*
G01X1229607D02*
X1229017Y696551D01*
G01D02*
X1223001D01*
G01D02*
X1217850Y691400D01*
G01X1251600Y701900D02*
X1222966D01*
G01X1252056Y703000D02*
X1222510D01*
G01X1231107Y697141D02*
X1229607D01*
G01X1224900Y752099D02*
Y738107D01*
G01D02*
X1246107Y716900D01*
G01X1246563Y718000D02*
X1226000Y738563D01*
G01D02*
Y752555D01*
G01X1233859Y278900D02*
G03X1234449Y279195I-26J790D01*
G01D02*
G02X1235039Y279490I616J-495D01*
G01D02*
X1236539D01*
G01D02*
G02X1237129Y279195I-26J-790D01*
G01D02*
G03X1237719Y278900I616J495D01*
G01D02*
X1239219D01*
G01D02*
G03X1239809Y279195I-26J790D01*
G01D02*
G02X1240399Y279490I616J-495D01*
G01D02*
X1241899D01*
G01D02*
G02X1242489Y279195I-26J-790D01*
G01D02*
G03X1243079Y278900I616J495D01*
G01D02*
X1252204D01*
G01X1238665Y286300D02*
X1247977D01*
G01D02*
G03X1248283Y286312I11J3621D01*
G01D02*
G03X1248798Y286394I-310J3608D01*
G01D02*
G03X1250537Y287361I-822J3526D01*
G01X1238665Y285200D02*
X1248377D01*
G01D02*
G02X1249402Y284776I1J-1449D01*
G01X1233846Y314135D02*
G02X1237293Y312707I0J-4874D01*
G01D02*
X1238000Y312000D01*
G01D02*
G03X1239569Y311350I1569J1569D01*
G01D02*
X1251820D01*
G01X1233845Y313035D02*
G02X1236515Y311929I1J-3774D01*
G01D02*
X1237222Y311222D01*
G01D02*
G03X1239568Y310250I2347J2347D01*
G01D02*
X1251820D01*
G01X1237616Y332117D02*
X1245755Y323978D01*
G01D02*
G03X1248358Y322900I2603J2603D01*
G01D02*
X1251953D01*
G01X1236838Y331339D02*
X1244977Y323200D01*
G01D02*
G03X1248358Y321800I3380J3381D01*
G01D02*
X1251410D01*
G01X1251005Y696551D02*
X1245911D01*
G01D02*
X1245321Y697141D01*
G01X1243821D02*
X1243231Y696551D01*
G01D02*
X1241731D01*
G01D02*
X1241141Y697141D01*
G01X1239641D02*
X1239051Y696551D01*
G01D02*
X1237551D01*
G01D02*
X1236961Y697141D01*
G01X1235461D02*
X1234871Y696551D01*
G01X1245321Y697141D02*
X1243821D01*
G01X1241141D02*
X1239641D01*
G01X1236961D02*
X1235461D01*
G01X1246107Y716900D02*
X1256044D01*
G01X1256500Y718000D02*
X1246563D01*
G01X1252204Y278900D02*
G03X1254377Y279800I0J3073D01*
G01D02*
X1255877Y281300D01*
G01D02*
G03X1257477Y285163I-3862J3862D01*
G01D02*
Y290168D01*
G01X1252204Y277800D02*
G03X1255155Y279022I0J4173D01*
G01D02*
X1256655Y280522D01*
G01D02*
G03X1258577Y285162I-4640J4640D01*
G01D02*
Y290169D01*
G01X1249402Y284776D02*
X1250677Y283500D01*
G01X1257477Y290168D02*
G03X1256999Y291322I-1631J0D01*
G01D02*
X1256988Y291332D01*
G01D02*
G02X1256968Y291353I299J305D01*
G01D02*
X1256967Y291354D01*
G01D02*
G02X1256133Y293399I2091J2045D01*
G01D02*
Y294648D01*
G01D02*
G02X1257222Y297278I3719J0D01*
G01D02*
G02X1259224Y298049I1868J-1867D01*
G01D02*
G03X1260577Y299335I65J1286D01*
G01D02*
Y299968D01*
G01X1258577Y290169D02*
G03X1257777Y292100I-2731J0D01*
G01D02*
X1257768Y292110D01*
G01D02*
G02X1257233Y293400I1290J1291D01*
G01D02*
Y294648D01*
G01D02*
G02X1258000Y296500I2619J0D01*
G01D02*
G02X1259168Y296949I1089J-1090D01*
G01D02*
G02X1260179Y296500I-78J-1539D01*
G01D02*
X1260577Y296102D01*
G01X1250537Y287361D02*
X1250677Y287500D01*
G01X1251820Y311350D02*
G03X1252173Y311496I0J500D01*
G01D02*
X1253477Y312800D01*
G01X1251820Y310250D02*
G02X1252173Y310104I0J-500D01*
G01D02*
X1253477Y308800D01*
G01D02*
X1253577D01*
G01X1251953Y322900D02*
G03X1252677Y323200I0J1024D01*
G01D02*
G03X1253177Y324407I-1207J1207D01*
G01D02*
Y324500D01*
G01X1251410Y321800D02*
G02X1252202Y321472I0J-1120D01*
G01D02*
X1253177Y320500D01*
G01X1269956Y700400D02*
X1264956Y695400D01*
G01D02*
X1258100D01*
G01D02*
X1251600Y701900D01*
G01X1269500Y701500D02*
X1264500Y696500D01*
G01D02*
X1258556D01*
G01D02*
X1252056Y703000D01*
G01X1281956Y690400D02*
X1255600D01*
G01D02*
X1250549Y695451D01*
G01X1281500Y691500D02*
X1256056D01*
G01D02*
X1251005Y696551D01*
G01X1256044Y716900D02*
X1266044Y706900D01*
G01X1266500Y708000D02*
X1256500Y718000D01*
G01X1286456Y694900D02*
X1281956Y690400D01*
G01X1286000Y696000D02*
X1281500Y691500D01*
G01X1309044Y700400D02*
X1269956D01*
G01X1309500Y701500D02*
X1269500D01*
G01X1266044Y706900D02*
X1313044D01*
G01X1313500Y708000D02*
X1266500D01*
G01X1307544Y694900D02*
X1286456D01*
G01X1308000Y696000D02*
X1286000D01*
G01X1320944Y688500D02*
X1309044Y700400D01*
G01X1321400Y689600D02*
X1309500Y701500D01*
G01X1319544Y682900D02*
X1307544Y694900D01*
G01X1320000Y684000D02*
X1308000Y696000D01*
G01X1313044Y706900D02*
X1324244Y695700D01*
G01X1324700Y696800D02*
X1313500Y708000D01*
G01X1332292Y687910D02*
X1330792D01*
G01D02*
X1330202Y688500D01*
G01D02*
X1328702D01*
G01D02*
X1328112Y687910D01*
G01D02*
X1326612D01*
G01D02*
X1326022Y688500D01*
G01D02*
X1320944D01*
G01X1368956Y689600D02*
X1321400D01*
G01X1324244Y695700D02*
X1327553D01*
G01D02*
X1328143Y695110D01*
G01D02*
X1329643D01*
G01D02*
X1330233Y695700D01*
G01D02*
X1331733D01*
G01X1371256Y696800D02*
X1324700D01*
G01X1364600Y682900D02*
X1319544D01*
G01X1339431Y684000D02*
X1320000D01*
G01X1351439Y688500D02*
X1337062D01*
G01D02*
X1336472Y687910D01*
G01D02*
X1334972D01*
G01D02*
X1334382Y688500D01*
G01D02*
X1332882D01*
G01D02*
X1332292Y687910D01*
G01X1331733Y695700D02*
X1332323Y695110D01*
G01D02*
X1333823D01*
G01D02*
X1334413Y695700D01*
G01D02*
X1335913D01*
G01D02*
X1336503Y695110D01*
G01D02*
X1338003D01*
G01D02*
X1338593Y695700D01*
G01D02*
X1341734D01*
G01D02*
X1342324Y695110D01*
G01D02*
X1343824D01*
G01D02*
X1344414Y695700D01*
G01D02*
X1345914D01*
G01D02*
X1346504Y695110D01*
G01D02*
X1348004D01*
G01X1348381Y684590D02*
X1347791Y684000D01*
G01D02*
X1346291D01*
G01D02*
X1345701Y684590D01*
G01D02*
X1344201D01*
G01D02*
X1343611Y684000D01*
G01D02*
X1342111D01*
G01D02*
X1341521Y684590D01*
G01D02*
X1340021D01*
G01D02*
X1339431Y684000D01*
G01X1368500Y688500D02*
X1362479D01*
G01D02*
X1361889Y687910D01*
G01D02*
X1360389D01*
G01D02*
X1359799Y688500D01*
G01D02*
X1358299D01*
G01D02*
X1357709Y687910D01*
G01D02*
X1356209D01*
G01D02*
X1355619Y688500D01*
G01D02*
X1354119D01*
G01D02*
X1353529Y687910D01*
G01D02*
X1352029D01*
G01D02*
X1351439Y688500D01*
G01X1348004Y695110D02*
X1348594Y695700D01*
G01D02*
X1350094D01*
G01D02*
X1350684Y695110D01*
G01D02*
X1352184D01*
G01D02*
X1352774Y695700D01*
G01D02*
X1357911D01*
G01D02*
X1358501Y695110D01*
G01D02*
X1360001D01*
G01D02*
X1360591Y695700D01*
G01D02*
X1362091D01*
G01D02*
X1362681Y695110D01*
G01D02*
X1364181D01*
G01D02*
X1364771Y695700D01*
G01X1365056Y684000D02*
X1350471D01*
G01D02*
X1349881Y684590D01*
G01D02*
X1348381D01*
G01X1377996Y607382D02*
X1376878Y608500D01*
G01D02*
X1375000D01*
G01D02*
X1372500Y611000D01*
G01D02*
Y629000D01*
G01X1377996Y610847D02*
X1376749Y609600D01*
G01D02*
X1375456D01*
G01D02*
X1373600Y611456D01*
G01D02*
Y628544D01*
G01X1380925Y598475D02*
X1379500Y599900D01*
G01D02*
X1373600D01*
G01D02*
X1367500Y606000D01*
G01D02*
Y632000D01*
G01X1380925Y602035D02*
X1379890Y601000D01*
G01D02*
X1374056D01*
G01D02*
X1368600Y606456D01*
G01D02*
Y631544D01*
G01X1372500Y629000D02*
X1383000Y639500D01*
G01X1373600Y628544D02*
X1384100Y639044D01*
G01X1367500Y632000D02*
X1377000Y641500D01*
G01D02*
Y670500D01*
G01X1368600Y631544D02*
X1378100Y641044D01*
G01D02*
Y656209D01*
G01D02*
X1378690Y656799D01*
G01D02*
Y658299D01*
G01D02*
X1378100Y658889D01*
G01D02*
Y660389D01*
G01D02*
X1378690Y660979D01*
G01D02*
Y662479D01*
G01D02*
X1378100Y663069D01*
G01D02*
Y664569D01*
G01X1383000Y674000D02*
X1368500Y688500D01*
G01X1384100Y674456D02*
X1368956Y689600D01*
G01X1377000Y670500D02*
X1364600Y682900D01*
G01X1378100Y664569D02*
X1378690Y665159D01*
G01D02*
Y666659D01*
G01D02*
X1378100Y667249D01*
G01D02*
Y670956D01*
G01D02*
X1375434Y673622D01*
G01D02*
Y674457D01*
G01D02*
X1374373Y675517D01*
G01D02*
X1373539D01*
G01D02*
X1365056Y684000D01*
G01X1364771Y695700D02*
X1370800D01*
G01D02*
X1372476Y694024D01*
G01D02*
Y693190D01*
G01D02*
X1373536Y692129D01*
G01D02*
X1374371D01*
G01D02*
X1375431Y691069D01*
G01D02*
Y690234D01*
G01D02*
X1376492Y689174D01*
G01D02*
X1377326D01*
G01D02*
X1378387Y688113D01*
G01D02*
Y687279D01*
G01D02*
X1379448Y686218D01*
G01D02*
X1380282D01*
G01D02*
X1382413Y684087D01*
G01X1389600Y678456D02*
X1371256Y696800D01*
G01X1382900Y582680D02*
X1381415Y581195D01*
G01X1385135D02*
X1384000Y582330D01*
G01X1388500Y678000D02*
Y597000D01*
G01D02*
X1382900Y591400D01*
G01D02*
Y582680D01*
G01X1384000Y582330D02*
Y590944D01*
G01D02*
X1389600Y596544D01*
G01D02*
Y678456D01*
G01X1380925Y598315D02*
Y598475D01*
G01X1383000Y639500D02*
Y674000D01*
G01X1384100Y639044D02*
Y674456D01*
G01X1384308Y682192D02*
X1388500Y678000D01*
G01X1382413Y684087D02*
Y683253D01*
G01D02*
X1383473Y682192D01*
G01D02*
X1384308D01*
G54D12*
G01X1Y-17717D02*
G03X7875Y-25591I7874J0D01*
G01X1Y299252D02*
Y-10394D01*
G01Y-17717D02*
G03X7875Y-25591I7874J0D01*
G01X1Y299252D02*
Y-10394D01*
G01Y-17717D02*
Y-10394D01*
G01D02*
Y-17723D01*
G01X0Y11811D02*
Y0D01*
G01X92520Y299252D02*
X1D01*
G01X92520D02*
X1D01*
G01X1008465Y988189D02*
G03X988780Y968504I0J-19685D01*
G01Y775591D01*
G02X984843Y771654I-3937J0D01*
G01X925787D01*
G02X921850Y775591I0J3937D01*
G01Y968504D01*
G03X902165Y988189I-19685J0D01*
G01X800984D01*
G02X797047Y992126I0J3937D01*
G01Y1021653D01*
X795078Y1023622D01*
X754921D01*
X752952Y1021653D01*
X752953Y1018110D01*
Y994291D01*
G02X745472I-3740J0D01*
G01Y1021653D01*
X743504Y1023622D01*
X719094D01*
X717126Y1021653D01*
Y992126D01*
G02X713189Y988189I-3937J0D01*
G01X600984D01*
G02X597047Y992126I0J3937D01*
G01Y1021653D01*
X595078Y1023622D01*
X554921D01*
X552952Y1021653D01*
X552953Y1018110D01*
Y994291D01*
G02X545472I-3741J0D01*
G01Y1021653D01*
X543504Y1023622D01*
X267126D01*
X265157Y1021653D01*
Y992126D01*
G02X261220Y988189I-3937J0D01*
G01X191535D01*
G02X187598Y992126I0J3937D01*
G01Y1021653D01*
X185630Y1023622D01*
X145472D01*
X143504Y1021653D01*
Y994291D01*
G02X136024I-3740J0D01*
G01Y1018110D01*
X136023Y1021653D01*
X134055Y1023622D01*
X109645D01*
X107677Y1021653D01*
Y992126D01*
G02X103740Y988189I-3937J0D01*
G01X19685D01*
G03X0Y968504I0J-19685D01*
G01Y318937D01*
G03X11811Y307126I11811J0D01*
G01X100394D01*
G02X108268Y299252I0J-7874D01*
G01Y236260D01*
G03X116142Y228386I7874J0D01*
G01X239961D01*
G02X243898Y224449I0J-3937D01*
G01Y70866D01*
G03X247835Y66929I3937J0D01*
G01X289173D01*
G02X293110Y62992I0J-3937D01*
G01Y3937D01*
G03X297047Y0I3937J0D01*
G01X1108209D01*
G03X1112146Y3937I0J3937D01*
G01Y210630D01*
G02X1116083Y214567I3937J0D01*
G01X1194823D01*
G02X1198760Y210630I0J-3937D01*
G01Y179134D01*
G03X1202697Y175197I3937J0D01*
G02X1206634Y171260I0J-3937D01*
G01Y3937D01*
G03X1210571Y0I3937J0D01*
G01X1396063D01*
G03X1400000Y3937I0J3937D01*
G01Y968504D01*
G03X1380315Y988189I-19685J0D01*
G01X1008465D01*
G01X0Y318937D02*
G03X11811Y307126I11811J0D01*
G01X0Y968503D02*
Y318937D01*
G01X19685Y988189D02*
G03X0Y968503I0J-19685D01*
G01X43950Y996063D02*
X1D01*
G01X43950D02*
X1D01*
G01Y1008622D02*
Y996063D01*
G01Y1008622D02*
Y996063D01*
G01X15001Y1023622D02*
G03X1Y1008622I0J-15000D01*
G01X15001Y1023622D02*
G03X1Y1008622I0J-15000D01*
G01X7875Y-25591D02*
X45337D01*
G01X7875D02*
X45337D01*
G01X11811Y307126D02*
X100394D01*
G01X10710Y1008622D02*
G03X19292I4291J0D01*
G01D02*
G03X10710I-4291J0D01*
G01X99804Y1023622D02*
X15001D01*
G01X99804D02*
X15001D01*
G01X103740Y988189D02*
X19685D01*
G01X53211Y-25591D02*
G03X45337I-3937J0D01*
G01X53211D02*
G03X45337I-3937J0D01*
G01X53211D02*
G03X45337I-3937J0D01*
G01X53211D02*
G03X45337I-3937J0D01*
G01X43950Y988189D02*
G03Y996063I0J3937D01*
G01Y988189D02*
G03Y996063I0J3937D01*
G01X53211Y-25591D02*
X1392127D01*
G01X53211D02*
X1392127D01*
G01X69147Y996063D02*
G03Y988189I0J-3937D01*
G01Y996063D02*
G03Y988189I0J-3937D01*
G01X99804Y996063D02*
X69147D01*
G01X99804D02*
X69147D01*
G01X94412Y72220D02*
G03X85830Y72219I-4291J-1D01*
G01D02*
G03X94412Y72220I4291J0D01*
G01X100394Y291377D02*
G03X92520Y299252I-7874J1D01*
G01X100394Y291377D02*
G03X92520Y299252I-7874J1D01*
G01X99804Y1023622D02*
Y996063D01*
G01Y1023622D02*
Y996063D01*
G01X100394Y236259D02*
G03X116142Y220511I15748J0D01*
G01D02*
X232088D01*
G01X100394Y236259D02*
G03X116142Y220511I15748J0D01*
G01D02*
X232088D01*
G01X116142Y228385D02*
X239961D01*
G01X108268Y236259D02*
G03X116142Y228385I7874J0D01*
G01X108268Y299252D02*
Y236259D01*
G01X100395Y240899D02*
X100394Y236259D01*
G01X100395Y240899D02*
X100394Y236259D01*
G01X108269Y240899D02*
G03X100395I-3937J0D01*
G01X108269D02*
G03X100395I-3937J0D01*
G01Y266096D02*
G03X108269I3937J-1D01*
G01X100395D02*
G03X108269I3937J-1D01*
G01X100395D02*
X100394Y291377D01*
G01X100395Y266096D02*
X100394Y291377D01*
G01X108268Y299252D02*
G03X100394Y307126I-7874J0D01*
G01X103740Y988189D02*
G03X107677Y992126I0J3937D01*
G01Y1018109D02*
Y992126D01*
G01X136024Y1018109D02*
X136023Y1021653D01*
X134055Y1023622D01*
X109645D01*
X107677Y1021653D01*
Y1018109D01*
G01X136024Y994290D02*
G03X143505I3740J0D01*
G01X136024D02*
Y1018109D01*
G01X143504D02*
Y994290D01*
G01X187598Y1018109D02*
Y1021653D01*
X185630Y1023622D01*
X145472D01*
X143504Y1021653D01*
Y1018109D01*
G01X151575Y220511D02*
X226378D01*
G01X151575D02*
X226378D01*
G01X187598Y992126D02*
Y1018109D01*
G01Y992126D02*
G03X191535Y988189I3937J0D01*
G01X261220D02*
X191535D01*
G01X212681Y996063D02*
X195473D01*
G01D02*
Y1023622D01*
G01X212681Y996063D02*
X195473D01*
G01D02*
Y1023622D01*
G01D02*
X257284D01*
G01X195473D02*
X257284D01*
G01X212681Y988189D02*
G03Y996063I0J3937D01*
G01Y988189D02*
G03Y996063I0J3937D01*
G01X222751Y1008622D02*
G03X231333I4291J0D01*
G01D02*
G03X222751I-4291J0D01*
G01X243898Y70866D02*
G03X247835Y66928I3937J-1D01*
G01X243898Y224448D02*
Y70866D01*
G01X236025Y164487D02*
Y70866D01*
G01D02*
G03X247836Y59055I11811J0D01*
G01X236025Y164487D02*
Y70866D01*
G01D02*
G03X247836Y59055I11811J0D01*
G01X243899Y164487D02*
G03X236025I-3937J0D01*
G01X243899D02*
G03X236025I-3937J0D01*
G01Y189684D02*
G03X243899I3937J0D01*
G01X236025D02*
G03X243899I3937J0D01*
G01X236025D02*
Y216574D01*
G01Y189684D02*
Y216574D01*
G01D02*
G03X232088Y220511I-3937J0D01*
G01X236025Y216574D02*
G03X232088Y220511I-3937J0D01*
G01X243898Y224448D02*
G03X239961Y228385I-3937J0D01*
G01X237877Y996063D02*
G03Y988189I0J-3937D01*
G01Y996063D02*
G03Y988189I0J-3937D01*
G01X257284Y996063D02*
X237877D01*
G01X257284D02*
X237877D01*
G01X247835Y66929D02*
X289174D01*
G01X247836Y59055D02*
X285237D01*
G01X247836D02*
X285237D01*
G01X261220Y988189D02*
G03X265157Y992126I0J3937D01*
G01X257284Y1023622D02*
Y996063D01*
G01Y1023622D02*
Y996063D01*
G01X265157Y1018109D02*
Y992126D01*
G01X545472Y1018109D02*
Y1021653D01*
X543504Y1023622D01*
X267126D01*
X265157Y1021653D01*
Y1018109D01*
G01X293111Y3937D02*
G03X297047Y0I3937J0D01*
G01X293110Y62992D02*
Y3937D01*
G01X285237D02*
G03X297048Y-7874I11811J0D01*
G01X285237Y59055D02*
Y3937D01*
G01D02*
G03X297048Y-7874I11811J0D01*
G01X285237Y59055D02*
Y3937D01*
G01X293111Y62992D02*
G03X289174Y66929I-3937J0D01*
G01X297047Y0D02*
X1108209D01*
G01X297037Y-7874D02*
X301187D01*
G01D02*
G03Y0I0J3937D01*
G01X297037Y-7874D02*
X301187D01*
G01D02*
G03Y0I0J3937D01*
G01X318510Y-7874D02*
X515333D01*
G01X318510Y0D02*
G03Y-7874I0J-3937D01*
G01D02*
X515333D01*
G01X318510Y0D02*
G03Y-7874I0J-3937D01*
G01X515302D02*
G03Y0I0J3937D01*
G01Y-7874D02*
G03Y0I0J3937D01*
G01X540499Y-7874D02*
X727049D01*
G01X540499Y0D02*
G03Y-7874I0J-3937D01*
G01D02*
X727049D01*
G01X540499Y0D02*
G03Y-7874I0J-3937D01*
G01X545472Y994290D02*
G03X552953I3740J1D01*
G01X545472D02*
Y1018109D01*
G01X552953D02*
Y994290D01*
G01X597047Y1018109D02*
Y1021653D01*
X595078Y1023622D01*
X554921D01*
X552952Y1021653D01*
X552953Y1018109D01*
G01X597047Y992126D02*
Y1018109D01*
G01X597048Y992126D02*
G03X600984Y988189I3937J0D01*
G01X713189D02*
X600984D01*
G01X641198Y996063D02*
X604922D01*
G01D02*
Y1023622D01*
G01X641198Y996063D02*
X604922D01*
G01D02*
Y1023622D01*
G01D02*
X709253D01*
G01X604922D02*
X709253D01*
G01X641198Y988189D02*
G03Y996063I0J3937D01*
G01Y988189D02*
G03Y996063I0J3937D01*
G01X649684Y1008622D02*
G03X658266I4291J0D01*
G01D02*
G03X649684I-4291J0D01*
G01X666395Y996063D02*
G03Y988189I0J-3937D01*
G01Y996063D02*
G03Y988189I0J-3937D01*
G01X709253Y996063D02*
X666395D01*
G01X709253D02*
X666395D01*
G01X713189Y988189D02*
G03X717126Y992126I0J3937D01*
G01Y1018109D02*
Y992126D01*
G01X709253Y1023622D02*
Y996063D01*
G01Y1023622D02*
Y996063D01*
G01X745472Y1018109D02*
Y1021653D01*
X743504Y1023622D01*
X719094D01*
X717126Y1021653D01*
Y1018109D01*
G01X727049Y-7874D02*
G03Y0I0J3937D01*
G01Y-7874D02*
G03Y0I0J3937D01*
G01X752246Y-7874D02*
X984201D01*
G01X752246Y0D02*
G03Y-7874I0J-3937D01*
G01D02*
X984201D01*
G01X752246Y0D02*
G03Y-7874I0J-3937D01*
G01X745472Y994290D02*
G03X752953I3741J1D01*
G01X745472D02*
Y1018109D01*
G01X752953D02*
Y994290D01*
G01X797047Y1018109D02*
Y1021653D01*
X795078Y1023622D01*
X754921D01*
X752952Y1021653D01*
X752953Y1018109D01*
G01X797047Y992126D02*
Y1018109D01*
G01X797048Y992126D02*
G03X800984Y988189I3937J0D01*
G01X902165D02*
X800984D01*
G01X859109Y996063D02*
X804922D01*
G01D02*
Y1023622D01*
G01X859109Y996063D02*
X804922D01*
G01D02*
Y1023622D01*
G01D02*
X1325399D01*
G01X804922D02*
X1325399D01*
G01X859109Y988189D02*
G03Y996063I0J3937D01*
G01Y988189D02*
G03Y996063I0J3937D01*
G01X884306D02*
G03Y988189I0J-3937D01*
G01Y996063D02*
G03Y988189I0J-3937D01*
G01X902166Y996063D02*
X884306D01*
G01X902166D02*
X884306D01*
G01X921850Y968503D02*
G03X902165Y988189I-19685J1D01*
G01X929725Y968504D02*
G03X902166Y996063I-27559J0D01*
G01D02*
X902195D01*
G01X929725Y968504D02*
G03X902166Y996063I-27559J0D01*
G01D02*
X902195D01*
G01X921850Y775590D02*
Y968503D01*
G01Y775590D02*
G03X925787Y771653I3937J0D01*
G01X984843D02*
X925787D01*
G01X929725Y779527D02*
Y886881D01*
G01Y779527D02*
X980906D01*
G01X929725D02*
Y886881D01*
G01Y779527D02*
X980906D01*
G01X929725Y886881D02*
G03X921851I-3937J1D01*
G01X929725D02*
G03X921851I-3937J1D01*
G01Y912079D02*
G03X929725I3937J-1D01*
G01X921851D02*
G03X929725I3937J-1D01*
G01Y912078D02*
Y968504D01*
G01Y912078D02*
Y968504D01*
G01X959606Y850829D02*
G03X951024I-4291J0D01*
G01D02*
G03X959606I4291J0D01*
G01X984201Y-7874D02*
G03Y0I0J3937D01*
G01Y-7874D02*
G03Y0I0J3937D01*
G01X984843Y771653D02*
G03X988780Y775590I0J3937D01*
G01X980907Y886881D02*
X980906Y779527D01*
G01X980907Y886881D02*
X980906Y779527D01*
G01X988781Y886881D02*
G03X980907I-3937J1D01*
G01X988781D02*
G03X980907I-3937J1D01*
G01Y912079D02*
G03X988781I3937J-1D01*
G01X980907D02*
G03X988781I3937J-1D01*
G01X980907D02*
X980906Y968504D01*
G01X980907Y912079D02*
X980906Y968504D01*
G01X1008465Y996063D02*
G03X980906Y968504I0J-27559D01*
G01X1008465Y996063D02*
G03X980906Y968504I0J-27559D01*
G01X1011417Y237795D02*
X1005118D01*
G02Y250394I0J6300D01*
G01X1011417D01*
G02Y237795I0J-6299D01*
G01Y405118D02*
X1005118D01*
G02Y417717I0J6300D01*
G01X1011417D01*
G02Y405118I0J-6299D01*
G01X988780Y968503D02*
Y775590D01*
G01X1008465Y988189D02*
G03X988780Y968503I0J-19685D01*
G01X1009398Y-7874D02*
X1108229D01*
G01X1009398Y0D02*
G03Y-7874I-1J-3937D01*
G01D02*
X1108229D01*
G01X1009398Y0D02*
G03Y-7874I-1J-3937D01*
G01X1380315Y988189D02*
X1008465D01*
G01X1070592Y996063D02*
X1008466D01*
G01X1070592D02*
X1008466D01*
G01X1070592Y988189D02*
G03Y996063I0J3937D01*
G01Y988189D02*
G03Y996063I0J3937D01*
G01X1095789D02*
G03Y988189I0J-3937D01*
G01Y996063D02*
G03Y988189I0J-3937D01*
G01X1325399Y996063D02*
X1095789D01*
G01X1325399D02*
X1095789D01*
G01X1112146Y3937D02*
Y210629D01*
G01X1108209Y0D02*
G03X1112146Y3937I0J3937D01*
G01X1108208Y-7874D02*
G03X1120020Y3938I1J11811D01*
G01X1108208Y-7874D02*
G03X1120020Y3938I1J11811D01*
G01Y99950D02*
G03X1112146I-3937J0D01*
G01X1120020D02*
G03X1112146I-3937J0D01*
G01Y125147D02*
G03X1120020I3937J0D01*
G01X1112146D02*
G03X1120020I3937J0D01*
G01X1116083Y214566D02*
X1194824D01*
G01X1116083D02*
G03X1112146Y210629I0J-3937D01*
G01X1120020Y99950D02*
Y3938D01*
G01Y99950D02*
Y3938D01*
G01Y125147D02*
Y206693D01*
G01Y125147D02*
Y206693D01*
G01X1120021D02*
X1190887D01*
G01X1120021D02*
X1190887D01*
G01X1161386Y128841D02*
G03X1152804I-4291J0D01*
G01D02*
G03X1161386I4291J0D01*
G01X1198760Y3937D02*
G03X1210571Y-7874I11811J0D01*
G01X1198760Y3937D02*
G03X1210571Y-7874I11811J0D01*
G01X1198761Y97100D02*
X1198760Y3937D01*
G01X1198761Y97100D02*
X1198760Y3937D01*
G01X1206635Y97100D02*
G03X1198761I-3937J0D01*
G01X1206635D02*
G03X1198761I-3937J0D01*
G01Y122297D02*
G03X1206635I3937J0D01*
G01X1198761D02*
G03X1206635I3937J0D01*
G01X1198761D02*
Y168002D01*
G01Y122297D02*
Y168002D01*
G01X1190887Y179134D02*
G03X1198761Y167998I11811J0D01*
G01X1190887Y179134D02*
G03X1198761Y167998I11811J0D01*
G01X1198760Y179133D02*
G03X1202697Y175196I3937J0D01*
G01X1198760Y210629D02*
Y179133D01*
G01X1190887Y206693D02*
Y179134D01*
G01Y206693D02*
Y179134D01*
G01X1198760Y210629D02*
G03X1194824Y214566I-3937J0D01*
G01X1210571Y0D02*
X1396063D01*
G01X1206634Y3937D02*
G03X1210571Y0I3937J0D01*
G01X1206634Y171259D02*
Y3937D01*
G01X1210552Y-7874D02*
X1210572D01*
G01D02*
G03Y0I0J3937D01*
G01X1210552Y-7874D02*
X1210572D01*
G01D02*
G03Y0I0J3937D01*
G01X1206634Y171259D02*
G03X1202697Y175196I-3937J0D01*
G01X1226320Y-7874D02*
X1380317D01*
G01X1226320Y0D02*
G03Y-7874I0J-3937D01*
G01D02*
X1380317D01*
G01X1226320Y0D02*
G03Y-7874I0J-3937D01*
G01X1230315Y149213D02*
X1224016D01*
G02Y161811I0J6299D01*
G01X1230315D01*
G02Y149213I0J-6299D01*
G01Y405118D02*
X1224016D01*
G02Y417717I0J6300D01*
G01X1230315D01*
G02Y405118I0J-6299D01*
G01X1354801Y996063D02*
X1325399D01*
G01X1354801D02*
X1325399D01*
G01Y1023622D02*
X1385001D01*
G01X1325399D02*
X1385001D01*
G01X1354801Y988189D02*
G03Y996063I0J3937D01*
G01Y988189D02*
G03Y996063I0J3937D01*
G01X1380316Y-7874D02*
G03Y0I0J3937D01*
G01Y-7874D02*
G03Y0I0J3937D01*
G01X1400000Y968503D02*
G03X1380315Y988189I-19685J1D01*
G01X1379998Y996063D02*
G03Y988189I0J-3937D01*
G01Y996063D02*
G03Y988189I0J-3937D01*
G01X1400001Y996063D02*
X1379998D01*
G01X1400001D02*
X1379998D01*
G01X1392127Y-25591D02*
G03X1400001Y-17717I0J7874D01*
G01X1392167Y-15015D02*
G03X1383585I-4291J0D01*
G01D02*
G03X1392167I4291J0D01*
G01X1392127Y-25591D02*
G03X1400001Y-17717I0J7874D01*
G01X1396063Y0D02*
G03X1400000Y3937I0J3937D01*
G01X1396064Y-7874D02*
X1400001D01*
G01X1396064Y0D02*
G03Y-7874I0J-3937D01*
G01D02*
X1400001D01*
G01X1396064Y0D02*
G03Y-7874I0J-3937D01*
G01X1380710Y1008622D02*
G03X1389292I4291J0D01*
G01D02*
G03X1380710I-4291J0D01*
G01X1400001D02*
G03X1385001Y1023622I-15000J0D01*
G01X1400001Y1008622D02*
G03X1385001Y1023622I-15000J0D01*
G01X1400001Y-17717D02*
Y-7874D01*
G01Y-17717D02*
Y-7874D01*
G01X1400000Y3937D02*
Y968503D01*
G01X1400001Y996063D02*
Y1008622D01*
G01Y996063D02*
Y1008622D01*
G54D13*
G01X363339Y150982D02*
X361107Y153214D01*
G01D02*
Y153605D01*
G01D02*
X361046Y153666D01*
G01X362808Y150452D02*
X360574Y152686D01*
G01D02*
X360187D01*
G01D02*
X360126Y152747D01*
G01X368600Y134646D02*
X366800D01*
G01X368800Y144105D02*
X367100D01*
G01X368329Y151956D02*
X366922Y150549D01*
G01D02*
G02X366200Y150250I-722J722D01*
G01D02*
X365107D01*
G01D02*
G02X363339Y150982I0J2500D01*
G01X368333Y148827D02*
G03X366708Y149500I-1625J-1625D01*
G01D02*
X365106D01*
G01D02*
G02X362808Y150452I0J3250D01*
M02*
